FILE_TYPE = MACRO_DRAWING;
SET COLOR_WIRE YELLOW;
SET COLOR_PROP MONO;
SET COLOR_DOT WHITE;
SET COLOR_ARC YELLOW;
SET COLOR_BODY GREEN;
SET COLOR_NOTE MONO;
SET PROP_DISPLAY VALUE;
SET PAGE_NUMBER P100;
FORCEADD OFFPAGE..2
(-1475 3625);
FORCEPROP 2 LAST $XR1 78 
J 0
(-1196 3625);
DISPLAY 0.638298 (-1196 3625);
PAINT MONO (-1196 3625);
FORCEPROP 2 LAST $XR0 77 
J 0
(-1286 3625);
DISPLAY 0.638298 (-1286 3625);
PAINT MONO (-1286 3625);
FORCEPROP 2 LAST CDS_LIB mstr_standard
J 0
(-1475 3625);
PAINT MONO (-1475 3625);
DISPLAY INVISIBLE (-1475 3625);
FORCEPROP 1 LAST OFFPAGE TRUE
J 0
(-1150 3500);
PAINT GREEN (-1150 3500);
DISPLAY INVISIBLE (-1150 3500);
FORCEPROP 1 LAST COMMENT_BODY TRUE
J 0
(-1520 3530);
DISPLAY 1.170213 (-1520 3530);
PAINT GREEN (-1520 3530);
DISPLAY INVISIBLE (-1520 3530);
FORCEPROP 2 LAST PATH I1
J 0
(-1300 3700);
DISPLAY 1.021277 (-1300 3700);
PAINT ORANGE (-1300 3700);
DISPLAY INVISIBLE (-1300 3700);
FORCEADD PVDDQ_KLM..1
(-1900 2525);
FORCEPROP 3 LASTPIN (-1900 2475) SIG_NAME PVDDQ_KLM\g
J 0
(-1890 2485);
DISPLAY 0.659574 (-1890 2485);
PAINT MONO (-1890 2485);
DISPLAY INVISIBLE (-1890 2485);
FORCEPROP 1 LAST VOLTAGE 1.2V
J 0
(-1945 2482);
DISPLAY 0.340426 (-1945 2482);
PAINT SKYBLUE (-1945 2482);
DISPLAY INVISIBLE (-1945 2482);
FORCEPROP 2 LAST CDS_LIB mstr_symbols
J 0
(-1900 2525);
PAINT ORANGE (-1900 2525);
DISPLAY INVISIBLE (-1900 2525);
FORCEPROP 1 LAST BODY_TYPE PLUMBING
J 0
(-1945 2482);
DISPLAY 0.340426 (-1945 2482);
PAINT GREEN (-1945 2482);
DISPLAY INVISIBLE (-1945 2482);
FORCEPROP 1 LAST PATH I10
J 0
(-1850 2550);
DISPLAY 0.872340 (-1850 2550);
PAINT AQUA (-1850 2550);
DISPLAY INVISIBLE (-1850 2550);
FORCEPROP 1 LAST HDL_POWER PVDDQ_KLM
J 1
(-1900 2575);
DISPLAY 0.872340 (-1900 2575);
PAINT GREEN (-1900 2575);
DISPLAY INVISIBLE (-1900 2575);
FORCEADD RES..2
R 2
(-1900 2275);
FORCEPROP 1 LAST LOCATION R9M1
J 2
(-1945 2400);
DISPLAY 0.617021 (-1945 2400);
PAINT AQUA (-1945 2400);
FORCEPROP 1 LAST PART_NUMBER G21796-026
J 2
(-1940 2150);
DISPLAY 0.617021 (-1940 2150);
PAINT BLUE (-1940 2150);
FORCEPROP 1 LAST VALUE 1.00K
J 2
(-1945 2350);
DISPLAY 0.617021 (-1945 2350);
PAINT SKYBLUE (-1945 2350);
FORCEPROP 1 LAST TOLERANCE 1%
J 2
(-1945 2300);
DISPLAY 0.617021 (-1945 2300);
PAINT SKYBLUE (-1945 2300);
FORCEPROP 1 LAST PACK_TYPE 0402
J 2
(-1940 2100);
DISPLAY 0.617021 (-1940 2100);
PAINT SKYBLUE (-1940 2100);
FORCEPROP 1 LAST MATERIAL CHIP
J 2
(-1940 2200);
DISPLAY 0.617021 (-1940 2200);
PAINT SKYBLUE (-1940 2200);
FORCEPROP 1 LAST WATTAGE 1/16W
J 2
(-1940 2250);
DISPLAY 0.617021 (-1940 2250);
PAINT SKYBLUE (-1940 2250);
FORCEPROP 1 LASTPIN (-1900 2175) $PN 2
J 2
(-1905 2185);
DISPLAY 0.617021 (-1905 2185);
PAINT ORANGE (-1905 2185);
FORCEPROP 1 LASTPIN (-1900 2375) $PN 1
J 2
(-1905 2337);
DISPLAY 0.617021 (-1905 2337);
PAINT ORANGE (-1905 2337);
FORCEPROP 2 LAST BOM_COST SM_CONTROLLER
J 2
(-1900 2275);
PAINT MONO (-1900 2275);
DISPLAY INVISIBLE (-1900 2275);
FORCEPROP 2 LAST CDS_LIB mstr_discrete
J 0
(-1900 2275);
PAINT ORANGE (-1900 2275);
DISPLAY INVISIBLE (-1900 2275);
FORCEPROP 2 LAST SEC_TYPE 0402
J 0
(-1950 2500);
DISPLAY 1.021277 (-1950 2500);
PAINT ORANGE (-1950 2500);
DISPLAY INVISIBLE (-1950 2500);
FORCEPROP 2 LAST SEC 1
J 0
(-1950 2500);
DISPLAY 0.680851 (-1950 2500);
PAINT MONO (-1950 2500);
DISPLAY INVISIBLE (-1950 2500);
FORCEPROP 2 LAST CDS_LOCATION R9M1
J 2
(-1945 2400);
DISPLAY 0.617021 (-1945 2400);
PAINT AQUA (-1945 2400);
DISPLAY INVISIBLE (-1945 2400);
FORCEPROP 1 LAST PATH I11
J 2
(-1950 2450);
DISPLAY 0.978723 (-1950 2450);
PAINT WHITE (-1950 2450);
DISPLAY INVISIBLE (-1950 2450);
FORCEPROP 2 LAST ROOM MEM
J 2
(-1950 2450);
PAINT PEACH (-1950 2450);
DISPLAY INVISIBLE (-1950 2450);
FORCEADD OFFPAGE..1
(-2850 3625);
FORCEPROP 2 LAST $XR0 55 
J 0
(-3101 3625);
DISPLAY 0.638298 (-3101 3625);
PAINT MONO (-3101 3625);
FORCEPROP 2 LAST CDS_LIB mstr_standard
J 0
(-2850 3625);
PAINT MONO (-2850 3625);
DISPLAY INVISIBLE (-2850 3625);
FORCEPROP 1 LAST OFFPAGE TRUE
J 0
(-2525 3500);
PAINT GREEN (-2525 3500);
DISPLAY INVISIBLE (-2525 3500);
FORCEPROP 1 LAST COMMENT_BODY TRUE
J 0
(-2725 3525);
DISPLAY 1.170213 (-2725 3525);
PAINT GREEN (-2725 3525);
DISPLAY INVISIBLE (-2725 3525);
FORCEPROP 2 LAST PATH I12
J 0
(-2800 3700);
DISPLAY 1.021277 (-2800 3700);
PAINT ORANGE (-2800 3700);
DISPLAY INVISIBLE (-2800 3700);
FORCEADD RES..1
(-2125 1950);
FORCEPROP 1 LAST LOCATION R9M2
J 0
(-2150 2025);
DISPLAY 0.617021 (-2150 2025);
PAINT AQUA (-2150 2025);
FORCEPROP 1 LAST PART_NUMBER G21796-274
J 0
(-2250 1800);
DISPLAY 0.617021 (-2250 1800);
PAINT BLUE (-2250 1800);
FORCEPROP 1 LAST VALUE 2
J 2
(-2200 1900);
DISPLAY 0.617021 (-2200 1900);
PAINT SKYBLUE (-2200 1900);
FORCEPROP 1 LAST TOLERANCE 1.0%
J 0
(-2025 1850);
DISPLAY 0.617021 (-2025 1850);
PAINT SKYBLUE (-2025 1850);
FORCEPROP 1 LAST PACK_TYPE 0402
J 0
(-2250 1850);
DISPLAY 0.617021 (-2250 1850);
PAINT SKYBLUE (-2250 1850);
FORCEPROP 1 LAST MATERIAL CHIP
J 0
(-1900 1900);
DISPLAY 0.617021 (-1900 1900);
PAINT SKYBLUE (-1900 1900);
FORCEPROP 1 LAST WATTAGE 1/16W
J 2
(-1950 1900);
DISPLAY 0.617021 (-1950 1900);
PAINT SKYBLUE (-1950 1900);
FORCEPROP 1 LASTPIN (-2025 1950) $PN 2
J 0
(-2063 1962);
DISPLAY 0.617021 (-2063 1962);
PAINT MONO (-2063 1962);
FORCEPROP 1 LASTPIN (-2225 1950) $PN 1
J 0
(-2213 1962);
DISPLAY 0.617021 (-2213 1962);
PAINT MONO (-2213 1962);
FORCEPROP 2 LAST CDS_LIB mstr_discrete
J 0
(-2125 1950);
PAINT ORANGE (-2125 1950);
DISPLAY INVISIBLE (-2125 1950);
FORCEPROP 2 LAST SEC_TYPE 0402
J 0
(-2175 2150);
PAINT MONO (-2175 2150);
DISPLAY INVISIBLE (-2175 2150);
FORCEPROP 2 LAST BOM_COST PROC_SOCKET
J 0
(-2125 1950);
PAINT MONO (-2125 1950);
DISPLAY INVISIBLE (-2125 1950);
FORCEPROP 2 LAST SEC 1
J 0
(-2175 2150);
DISPLAY 0.936170 (-2175 2150);
PAINT MONO (-2175 2150);
DISPLAY INVISIBLE (-2175 2150);
FORCEPROP 2 LAST CDS_LOCATION R9M2
J 0
(-2150 2025);
DISPLAY 0.617021 (-2150 2025);
PAINT AQUA (-2150 2025);
DISPLAY INVISIBLE (-2150 2025);
FORCEPROP 1 LAST PATH I13
J 0
(-2175 2100);
DISPLAY 0.978723 (-2175 2100);
PAINT WHITE (-2175 2100);
DISPLAY INVISIBLE (-2175 2100);
FORCEPROP 0 LAST ROOM PROC
J 0
(-2200 1875);
DISPLAY 0.617021 (-2200 1875);
PAINT ORANGE (-2200 1875);
DISPLAY INVISIBLE (-2200 1875);
FORCEADD GND..1
(-2125 1300);
FORCEPROP 3 LASTPIN (-2125 1350) SIG_NAME GND\g
J 0
(-2115 1360);
DISPLAY 0.659574 (-2115 1360);
PAINT MONO (-2115 1360);
DISPLAY INVISIBLE (-2115 1360);
FORCEPROP 1 LAST VOLTAGE 0
J 0
(-2125 1300);
PAINT SKYBLUE (-2125 1300);
DISPLAY INVISIBLE (-2125 1300);
FORCEPROP 1 LAST SIZE 1B
J 0
(-2050 1250);
DISPLAY 1.170213 (-2050 1250);
PAINT GREEN (-2050 1250);
DISPLAY INVISIBLE (-2050 1250);
FORCEPROP 2 LAST CDS_LIB mstr_symbols
J 0
(-2125 1300);
PAINT MONO (-2125 1300);
DISPLAY INVISIBLE (-2125 1300);
FORCEPROP 1 LAST BODY_TYPE PLUMBING
J 0
(-2170 1257);
DISPLAY 0.340426 (-2170 1257);
PAINT GREEN (-2170 1257);
DISPLAY INVISIBLE (-2170 1257);
FORCEPROP 1 LAST PATH I14
J 0
(-2050 1300);
DISPLAY 0.872340 (-2050 1300);
PAINT AQUA (-2050 1300);
DISPLAY INVISIBLE (-2050 1300);
FORCEPROP 1 LAST HDL_POWER GND
J 0
(-2125 1450);
DISPLAY 1.170213 (-2125 1450);
PAINT GREEN (-2125 1450);
DISPLAY INVISIBLE (-2125 1450);
FORCEADD CAP_A..1
(-2350 1650);
FORCEPROP 1 LAST LOCATION C9M2
J 0
(-2300 1750);
DISPLAY 0.617021 (-2300 1750);
PAINT AQUA (-2300 1750);
FORCEPROP 1 LAST PART_NUMBER A36096-045
J 0
(-2300 1500);
DISPLAY 0.617021 (-2300 1500);
PAINT BLUE (-2300 1500);
FORCEPROP 1 LAST VALUE 0.01UF
J 0
(-2300 1700);
DISPLAY 0.617021 (-2300 1700);
PAINT SKYBLUE (-2300 1700);
FORCEPROP 1 LAST TOLERANCE 10%
J 0
(-2300 1600);
DISPLAY 0.617021 (-2300 1600);
PAINT SKYBLUE (-2300 1600);
FORCEPROP 1 LAST PACK_TYPE 0402V
J 0
(-2300 1450);
DISPLAY 0.617021 (-2300 1450);
PAINT SKYBLUE (-2300 1450);
FORCEPROP 1 LAST VOLTAGE 25V
J 0
(-2300 1650);
DISPLAY 0.617021 (-2300 1650);
PAINT SKYBLUE (-2300 1650);
FORCEPROP 1 LAST MATERIAL X7R
J 0
(-2300 1550);
DISPLAY 0.617021 (-2300 1550);
PAINT SKYBLUE (-2300 1550);
FORCEPROP 1 LASTPIN (-2350 1750) $PN 1
J 0
(-2340 1730);
DISPLAY 0.617021 (-2340 1730);
PAINT ORANGE (-2340 1730);
FORCEPROP 1 LASTPIN (-2350 1550) $PN 2
J 0
(-2340 1530);
DISPLAY 0.617021 (-2340 1530);
PAINT ORANGE (-2340 1530);
FORCEPROP 2 LAST CDS_LOCATION C9M2
J 0
(-2300 1750);
DISPLAY 0.617021 (-2300 1750);
PAINT AQUA (-2300 1750);
DISPLAY INVISIBLE (-2300 1750);
FORCEPROP 2 LAST BOM_COST SM_CONTROLLER
J 0
(-2350 1650);
PAINT MONO (-2350 1650);
DISPLAY INVISIBLE (-2350 1650);
FORCEPROP 2 LAST CDS_LIB dev_discrete
J 0
(-2350 1650);
PAINT ORANGE (-2350 1650);
DISPLAY INVISIBLE (-2350 1650);
FORCEPROP 2 LAST CDS_SEC 1
J 0
(-2300 1800);
PAINT ORANGE (-2300 1800);
DISPLAY INVISIBLE (-2300 1800);
FORCEPROP 2 LAST SEC_TYPE 0402V
J 0
(-2300 1850);
DISPLAY 1.021277 (-2300 1850);
PAINT ORANGE (-2300 1850);
DISPLAY INVISIBLE (-2300 1850);
FORCEPROP 2 LAST SEC 1
J 0
(-2300 1850);
DISPLAY 0.680851 (-2300 1850);
PAINT MONO (-2300 1850);
DISPLAY INVISIBLE (-2300 1850);
FORCEPROP 1 LAST PATH I15
J 0
(-2300 1800);
DISPLAY 0.978723 (-2300 1800);
PAINT WHITE (-2300 1800);
DISPLAY INVISIBLE (-2300 1800);
FORCEPROP 0 LAST ROOM MEM
J 0
(-2300 1400);
DISPLAY 0.978723 (-2300 1400);
PAINT ORANGE (-2300 1400);
DISPLAY INVISIBLE (-2300 1400);
FORCEADD OFFPAGE..1
(-2850 1950);
FORCEPROP 2 LAST $XR0 55 
J 0
(-3101 1950);
DISPLAY 0.638298 (-3101 1950);
PAINT MONO (-3101 1950);
FORCEPROP 2 LAST CDS_LIB mstr_standard
J 0
(-2850 1950);
PAINT MONO (-2850 1950);
DISPLAY INVISIBLE (-2850 1950);
FORCEPROP 1 LAST OFFPAGE TRUE
J 0
(-2525 1825);
PAINT GREEN (-2525 1825);
DISPLAY INVISIBLE (-2525 1825);
FORCEPROP 1 LAST COMMENT_BODY TRUE
J 0
(-2725 1850);
DISPLAY 1.170213 (-2725 1850);
PAINT GREEN (-2725 1850);
DISPLAY INVISIBLE (-2725 1850);
FORCEPROP 2 LAST PATH I16
J 0
(-2800 2025);
DISPLAY 1.021277 (-2800 2025);
PAINT ORANGE (-2800 2025);
DISPLAY INVISIBLE (-2800 2025);
FORCEADD PVDDQ_GHJ..1
(450 4200);
FORCEPROP 3 LASTPIN (450 4150) SIG_NAME PVDDQ_GHJ\g
J 0
(460 4160);
DISPLAY 0.659574 (460 4160);
PAINT MONO (460 4160);
DISPLAY INVISIBLE (460 4160);
FORCEPROP 1 LAST VOLTAGE 1.2V
J 0
(405 4157);
DISPLAY 0.340426 (405 4157);
PAINT SKYBLUE (405 4157);
DISPLAY INVISIBLE (405 4157);
FORCEPROP 2 LAST CDS_LIB mstr_symbols
J 0
(450 4200);
PAINT ORANGE (450 4200);
DISPLAY INVISIBLE (450 4200);
FORCEPROP 1 LAST BODY_TYPE PLUMBING
J 0
(405 4157);
DISPLAY 0.340426 (405 4157);
PAINT GREEN (405 4157);
DISPLAY INVISIBLE (405 4157);
FORCEPROP 1 LAST PATH I17
J 0
(500 4225);
DISPLAY 0.872340 (500 4225);
PAINT AQUA (500 4225);
DISPLAY INVISIBLE (500 4225);
FORCEPROP 1 LAST HDL_POWER PVDDQ_GHJ
J 1
(450 4250);
DISPLAY 0.872340 (450 4250);
PAINT GREEN (450 4250);
DISPLAY INVISIBLE (450 4250);
FORCEADD OFFPAGE..2
(875 3625);
FORCEPROP 2 LAST $XR1 80 
J 0
(1154 3625);
DISPLAY 0.638298 (1154 3625);
PAINT MONO (1154 3625);
FORCEPROP 2 LAST $XR0 79 
J 0
(1064 3625);
DISPLAY 0.638298 (1064 3625);
PAINT MONO (1064 3625);
FORCEPROP 2 LAST CDS_LIB mstr_standard
J 0
(875 3625);
PAINT MONO (875 3625);
DISPLAY INVISIBLE (875 3625);
FORCEPROP 1 LAST OFFPAGE TRUE
J 0
(1200 3500);
PAINT GREEN (1200 3500);
DISPLAY INVISIBLE (1200 3500);
FORCEPROP 1 LAST COMMENT_BODY TRUE
J 0
(830 3530);
DISPLAY 1.170213 (830 3530);
PAINT GREEN (830 3530);
DISPLAY INVISIBLE (830 3530);
FORCEPROP 2 LAST PATH I18
J 0
(1050 3700);
DISPLAY 1.021277 (1050 3700);
PAINT ORANGE (1050 3700);
DISPLAY INVISIBLE (1050 3700);
FORCEADD RES..2
R 2
(450 3950);
FORCEPROP 1 LAST VALUE 1.00K
J 2
(405 4025);
DISPLAY 0.617021 (405 4025);
PAINT SKYBLUE (405 4025);
FORCEPROP 1 LAST TOLERANCE 1%
J 2
(405 3975);
DISPLAY 0.617021 (405 3975);
PAINT SKYBLUE (405 3975);
FORCEPROP 1 LAST PACK_TYPE 0402
J 2
(410 3775);
DISPLAY 0.617021 (410 3775);
PAINT SKYBLUE (410 3775);
FORCEPROP 1 LAST MATERIAL CHIP
J 2
(410 3875);
DISPLAY 0.617021 (410 3875);
PAINT SKYBLUE (410 3875);
FORCEPROP 1 LAST WATTAGE 1/16W
J 2
(410 3925);
DISPLAY 0.617021 (410 3925);
PAINT SKYBLUE (410 3925);
FORCEPROP 1 LASTPIN (450 3850) $PN 2
J 2
(445 3860);
DISPLAY 0.617021 (445 3860);
PAINT ORANGE (445 3860);
FORCEPROP 1 LASTPIN (450 4050) $PN 1
J 2
(445 4012);
DISPLAY 0.617021 (445 4012);
PAINT ORANGE (445 4012);
FORCEPROP 1 LAST LOCATION R1G2
J 2
(405 4075);
DISPLAY 0.617021 (405 4075);
PAINT AQUA (405 4075);
FORCEPROP 1 LAST PART_NUMBER G21796-026
J 2
(410 3825);
DISPLAY 0.617021 (410 3825);
PAINT BLUE (410 3825);
FORCEPROP 2 LAST SEC_TYPE 0402
J 0
(400 4175);
DISPLAY 1.021277 (400 4175);
PAINT ORANGE (400 4175);
DISPLAY INVISIBLE (400 4175);
FORCEPROP 2 LAST BOM_COST SM_CONTROLLER
J 2
(450 3950);
PAINT MONO (450 3950);
DISPLAY INVISIBLE (450 3950);
FORCEPROP 2 LAST CDS_LIB mstr_discrete
J 0
(450 3950);
PAINT ORANGE (450 3950);
DISPLAY INVISIBLE (450 3950);
FORCEPROP 2 LAST SEC 1
J 0
(400 4175);
DISPLAY 0.680851 (400 4175);
PAINT MONO (400 4175);
DISPLAY INVISIBLE (400 4175);
FORCEPROP 2 LAST CDS_LOCATION R1G2
J 2
(405 4075);
DISPLAY 0.617021 (405 4075);
PAINT AQUA (405 4075);
DISPLAY INVISIBLE (405 4075);
FORCEPROP 1 LAST PATH I19
J 2
(400 4125);
DISPLAY 0.978723 (400 4125);
PAINT WHITE (400 4125);
DISPLAY INVISIBLE (400 4125);
FORCEPROP 2 LAST ROOM MEM
J 2
(400 4125);
PAINT PEACH (400 4125);
DISPLAY INVISIBLE (400 4125);
FORCEADD RES..2
R 2
(-1825 3300);
FORCEPROP 1 LAST LOCATION R1F6
J 2
(-1870 3425);
DISPLAY 0.617021 (-1870 3425);
PAINT AQUA (-1870 3425);
FORCEPROP 1 LAST PART_NUMBER G21796-026
J 2
(-1865 3175);
DISPLAY 0.617021 (-1865 3175);
PAINT BLUE (-1865 3175);
FORCEPROP 1 LAST VALUE 1.00K
J 2
(-1870 3375);
DISPLAY 0.617021 (-1870 3375);
PAINT SKYBLUE (-1870 3375);
FORCEPROP 1 LAST TOLERANCE 1%
J 2
(-1870 3325);
DISPLAY 0.617021 (-1870 3325);
PAINT SKYBLUE (-1870 3325);
FORCEPROP 1 LAST PACK_TYPE 0402
J 2
(-1865 3125);
DISPLAY 0.617021 (-1865 3125);
PAINT SKYBLUE (-1865 3125);
FORCEPROP 1 LAST MATERIAL CHIP
J 2
(-1865 3225);
DISPLAY 0.617021 (-1865 3225);
PAINT SKYBLUE (-1865 3225);
FORCEPROP 1 LAST WATTAGE 1/16W
J 2
(-1865 3275);
DISPLAY 0.617021 (-1865 3275);
PAINT SKYBLUE (-1865 3275);
FORCEPROP 1 LASTPIN (-1825 3200) $PN 2
J 2
(-1830 3210);
DISPLAY 0.617021 (-1830 3210);
PAINT ORANGE (-1830 3210);
FORCEPROP 1 LASTPIN (-1825 3400) $PN 1
J 2
(-1830 3362);
DISPLAY 0.617021 (-1830 3362);
PAINT ORANGE (-1830 3362);
FORCEPROP 2 LAST CDS_LIB mstr_discrete
J 0
(-1825 3300);
PAINT ORANGE (-1825 3300);
DISPLAY INVISIBLE (-1825 3300);
FORCEPROP 2 LAST BOM_COST SM_CONTROLLER
J 2
(-1825 3300);
PAINT MONO (-1825 3300);
DISPLAY INVISIBLE (-1825 3300);
FORCEPROP 2 LAST SEC_TYPE 0402
J 0
(-1875 3525);
DISPLAY 1.021277 (-1875 3525);
PAINT ORANGE (-1875 3525);
DISPLAY INVISIBLE (-1875 3525);
FORCEPROP 2 LAST SEC 1
J 0
(-1875 3525);
DISPLAY 0.680851 (-1875 3525);
PAINT MONO (-1875 3525);
DISPLAY INVISIBLE (-1875 3525);
FORCEPROP 2 LAST CDS_LOCATION R1F6
J 2
(-1870 3425);
DISPLAY 0.617021 (-1870 3425);
PAINT AQUA (-1870 3425);
DISPLAY INVISIBLE (-1870 3425);
FORCEPROP 1 LAST PATH I2
J 2
(-1875 3475);
DISPLAY 0.978723 (-1875 3475);
PAINT WHITE (-1875 3475);
DISPLAY INVISIBLE (-1875 3475);
FORCEPROP 2 LAST ROOM MEM
J 2
(-1875 3475);
PAINT PEACH (-1875 3475);
DISPLAY INVISIBLE (-1875 3475);
FORCEADD RES..2
R 2
(525 3300);
FORCEPROP 1 LAST LOCATION R1G3
J 2
(480 3425);
DISPLAY 0.617021 (480 3425);
PAINT AQUA (480 3425);
FORCEPROP 1 LAST PART_NUMBER G21796-026
J 2
(485 3175);
DISPLAY 0.617021 (485 3175);
PAINT BLUE (485 3175);
FORCEPROP 1 LAST VALUE 1.00K
J 2
(480 3375);
DISPLAY 0.617021 (480 3375);
PAINT SKYBLUE (480 3375);
FORCEPROP 1 LAST TOLERANCE 1%
J 2
(480 3325);
DISPLAY 0.617021 (480 3325);
PAINT SKYBLUE (480 3325);
FORCEPROP 1 LAST PACK_TYPE 0402
J 2
(485 3125);
DISPLAY 0.617021 (485 3125);
PAINT SKYBLUE (485 3125);
FORCEPROP 1 LAST MATERIAL CHIP
J 2
(485 3225);
DISPLAY 0.617021 (485 3225);
PAINT SKYBLUE (485 3225);
FORCEPROP 1 LAST WATTAGE 1/16W
J 2
(485 3275);
DISPLAY 0.617021 (485 3275);
PAINT SKYBLUE (485 3275);
FORCEPROP 1 LASTPIN (525 3200) $PN 2
J 2
(520 3210);
DISPLAY 0.617021 (520 3210);
PAINT ORANGE (520 3210);
FORCEPROP 1 LASTPIN (525 3400) $PN 1
J 2
(520 3362);
DISPLAY 0.617021 (520 3362);
PAINT ORANGE (520 3362);
FORCEPROP 2 LAST SEC_TYPE 0402
J 0
(475 3525);
DISPLAY 1.021277 (475 3525);
PAINT ORANGE (475 3525);
DISPLAY INVISIBLE (475 3525);
FORCEPROP 2 LAST BOM_COST SM_CONTROLLER
J 2
(525 3300);
PAINT MONO (525 3300);
DISPLAY INVISIBLE (525 3300);
FORCEPROP 2 LAST CDS_LIB mstr_discrete
J 0
(525 3300);
PAINT ORANGE (525 3300);
DISPLAY INVISIBLE (525 3300);
FORCEPROP 2 LAST SEC 1
J 0
(475 3525);
DISPLAY 0.680851 (475 3525);
PAINT MONO (475 3525);
DISPLAY INVISIBLE (475 3525);
FORCEPROP 2 LAST CDS_LOCATION R1G3
J 2
(480 3425);
DISPLAY 0.617021 (480 3425);
PAINT AQUA (480 3425);
DISPLAY INVISIBLE (480 3425);
FORCEPROP 1 LAST PATH I20
J 2
(475 3475);
DISPLAY 0.978723 (475 3475);
PAINT WHITE (475 3475);
DISPLAY INVISIBLE (475 3475);
FORCEPROP 2 LAST ROOM MEM
J 2
(475 3475);
PAINT PEACH (475 3475);
DISPLAY INVISIBLE (475 3475);
FORCEADD PVDDQ_KLM..1
(450 2525);
FORCEPROP 3 LASTPIN (450 2475) SIG_NAME PVDDQ_KLM\g
J 0
(460 2485);
DISPLAY 0.659574 (460 2485);
PAINT MONO (460 2485);
DISPLAY INVISIBLE (460 2485);
FORCEPROP 1 LAST VOLTAGE 1.2V
J 0
(405 2482);
DISPLAY 0.340426 (405 2482);
PAINT SKYBLUE (405 2482);
DISPLAY INVISIBLE (405 2482);
FORCEPROP 2 LAST CDS_LIB mstr_symbols
J 0
(450 2525);
PAINT ORANGE (450 2525);
DISPLAY INVISIBLE (450 2525);
FORCEPROP 1 LAST BODY_TYPE PLUMBING
J 0
(405 2482);
DISPLAY 0.340426 (405 2482);
PAINT GREEN (405 2482);
DISPLAY INVISIBLE (405 2482);
FORCEPROP 1 LAST PATH I21
J 0
(500 2550);
DISPLAY 0.872340 (500 2550);
PAINT AQUA (500 2550);
DISPLAY INVISIBLE (500 2550);
FORCEPROP 1 LAST HDL_POWER PVDDQ_KLM
J 1
(450 2575);
DISPLAY 0.872340 (450 2575);
PAINT GREEN (450 2575);
DISPLAY INVISIBLE (450 2575);
FORCEADD RES..2
R 2
(450 2275);
FORCEPROP 1 LASTPIN (450 2375) $PN 1
J 2
(445 2337);
DISPLAY 0.617021 (445 2337);
PAINT ORANGE (445 2337);
FORCEPROP 1 LAST LOCATION R9L7
J 2
(405 2400);
DISPLAY 0.617021 (405 2400);
PAINT AQUA (405 2400);
FORCEPROP 1 LAST PART_NUMBER G21796-026
J 2
(410 2150);
DISPLAY 0.617021 (410 2150);
PAINT BLUE (410 2150);
FORCEPROP 1 LAST VALUE 1.00K
J 2
(405 2350);
DISPLAY 0.617021 (405 2350);
PAINT SKYBLUE (405 2350);
FORCEPROP 1 LAST TOLERANCE 1%
J 2
(405 2300);
DISPLAY 0.617021 (405 2300);
PAINT SKYBLUE (405 2300);
FORCEPROP 1 LAST PACK_TYPE 0402
J 2
(410 2100);
DISPLAY 0.617021 (410 2100);
PAINT SKYBLUE (410 2100);
FORCEPROP 1 LAST MATERIAL CHIP
J 2
(410 2200);
DISPLAY 0.617021 (410 2200);
PAINT SKYBLUE (410 2200);
FORCEPROP 1 LAST WATTAGE 1/16W
J 2
(410 2250);
DISPLAY 0.617021 (410 2250);
PAINT SKYBLUE (410 2250);
FORCEPROP 1 LASTPIN (450 2175) $PN 2
J 2
(445 2185);
DISPLAY 0.617021 (445 2185);
PAINT ORANGE (445 2185);
FORCEPROP 2 LAST SEC_TYPE 0402
J 0
(400 2500);
DISPLAY 1.021277 (400 2500);
PAINT ORANGE (400 2500);
DISPLAY INVISIBLE (400 2500);
FORCEPROP 2 LAST CDS_LIB mstr_discrete
J 0
(450 2275);
PAINT ORANGE (450 2275);
DISPLAY INVISIBLE (450 2275);
FORCEPROP 2 LAST BOM_COST SM_CONTROLLER
J 2
(450 2275);
PAINT MONO (450 2275);
DISPLAY INVISIBLE (450 2275);
FORCEPROP 2 LAST SEC 1
J 0
(400 2500);
DISPLAY 0.680851 (400 2500);
PAINT MONO (400 2500);
DISPLAY INVISIBLE (400 2500);
FORCEPROP 2 LAST CDS_LOCATION R9L7
J 2
(405 2400);
DISPLAY 0.617021 (405 2400);
PAINT AQUA (405 2400);
DISPLAY INVISIBLE (405 2400);
FORCEPROP 1 LAST PATH I22
J 2
(400 2450);
DISPLAY 0.978723 (400 2450);
PAINT WHITE (400 2450);
DISPLAY INVISIBLE (400 2450);
FORCEPROP 2 LAST ROOM MEM
J 2
(400 2450);
PAINT PEACH (400 2450);
DISPLAY INVISIBLE (400 2450);
FORCEADD OFFPAGE..2
(875 1950);
FORCEPROP 2 LAST $XR1 86 
J 0
(1154 1950);
DISPLAY 0.638298 (1154 1950);
PAINT MONO (1154 1950);
FORCEPROP 2 LAST $XR0 85 
J 0
(1064 1950);
DISPLAY 0.638298 (1064 1950);
PAINT MONO (1064 1950);
FORCEPROP 2 LAST CDS_LIB mstr_standard
J 0
(875 1950);
PAINT MONO (875 1950);
DISPLAY INVISIBLE (875 1950);
FORCEPROP 1 LAST OFFPAGE TRUE
J 0
(1200 1825);
PAINT GREEN (1200 1825);
DISPLAY INVISIBLE (1200 1825);
FORCEPROP 1 LAST COMMENT_BODY TRUE
J 0
(830 1855);
DISPLAY 1.170213 (830 1855);
PAINT GREEN (830 1855);
DISPLAY INVISIBLE (830 1855);
FORCEPROP 2 LAST PATH I23
J 0
(1050 2025);
DISPLAY 1.021277 (1050 2025);
PAINT ORANGE (1050 2025);
DISPLAY INVISIBLE (1050 2025);
FORCEADD RES..2
R 2
(525 1625);
FORCEPROP 1 LAST LOCATION R9L6
J 2
(480 1750);
DISPLAY 0.617021 (480 1750);
PAINT AQUA (480 1750);
FORCEPROP 1 LAST PART_NUMBER G21796-026
J 2
(485 1500);
DISPLAY 0.617021 (485 1500);
PAINT BLUE (485 1500);
FORCEPROP 1 LAST VALUE 1.00K
J 2
(480 1700);
DISPLAY 0.617021 (480 1700);
PAINT SKYBLUE (480 1700);
FORCEPROP 1 LAST TOLERANCE 1%
J 2
(480 1650);
DISPLAY 0.617021 (480 1650);
PAINT SKYBLUE (480 1650);
FORCEPROP 1 LAST PACK_TYPE 0402
J 2
(485 1450);
DISPLAY 0.617021 (485 1450);
PAINT SKYBLUE (485 1450);
FORCEPROP 1 LAST MATERIAL CHIP
J 2
(485 1550);
DISPLAY 0.617021 (485 1550);
PAINT SKYBLUE (485 1550);
FORCEPROP 1 LAST WATTAGE 1/16W
J 2
(485 1600);
DISPLAY 0.617021 (485 1600);
PAINT SKYBLUE (485 1600);
FORCEPROP 1 LASTPIN (525 1525) $PN 2
J 2
(520 1535);
DISPLAY 0.617021 (520 1535);
PAINT ORANGE (520 1535);
FORCEPROP 1 LASTPIN (525 1725) $PN 1
J 2
(520 1687);
DISPLAY 0.617021 (520 1687);
PAINT ORANGE (520 1687);
FORCEPROP 2 LAST SEC_TYPE 0402
J 0
(475 1850);
DISPLAY 1.021277 (475 1850);
PAINT ORANGE (475 1850);
DISPLAY INVISIBLE (475 1850);
FORCEPROP 2 LAST BOM_COST PROC_SOCKET
J 2
(525 1625);
PAINT MONO (525 1625);
DISPLAY INVISIBLE (525 1625);
FORCEPROP 2 LAST CDS_LIB mstr_discrete
J 0
(525 1625);
PAINT ORANGE (525 1625);
DISPLAY INVISIBLE (525 1625);
FORCEPROP 2 LAST SEC 1
J 0
(475 1850);
DISPLAY 0.680851 (475 1850);
PAINT MONO (475 1850);
DISPLAY INVISIBLE (475 1850);
FORCEPROP 2 LAST CDS_LOCATION R9L6
J 2
(480 1750);
DISPLAY 0.617021 (480 1750);
PAINT AQUA (480 1750);
DISPLAY INVISIBLE (480 1750);
FORCEPROP 1 LAST PATH I24
J 2
(475 1800);
DISPLAY 0.978723 (475 1800);
PAINT WHITE (475 1800);
DISPLAY INVISIBLE (475 1800);
FORCEPROP 2 LAST ROOM PROC
J 2
(475 1800);
PAINT PEACH (475 1800);
DISPLAY INVISIBLE (475 1800);
FORCEADD RES..1
(225 3625);
FORCEPROP 1 LAST LOCATION R1G1
J 0
(175 3675);
DISPLAY 0.617021 (175 3675);
PAINT AQUA (175 3675);
FORCEPROP 1 LAST PART_NUMBER G21796-274
J 0
(100 3475);
DISPLAY 0.617021 (100 3475);
PAINT BLUE (100 3475);
FORCEPROP 1 LAST VALUE 2
J 2
(150 3575);
DISPLAY 0.617021 (150 3575);
PAINT SKYBLUE (150 3575);
FORCEPROP 1 LAST TOLERANCE 1.0%
J 0
(325 3525);
DISPLAY 0.617021 (325 3525);
PAINT SKYBLUE (325 3525);
FORCEPROP 1 LAST PACK_TYPE 0402
J 0
(100 3525);
DISPLAY 0.617021 (100 3525);
PAINT SKYBLUE (100 3525);
FORCEPROP 1 LAST MATERIAL CHIP
J 0
(450 3575);
DISPLAY 0.617021 (450 3575);
PAINT SKYBLUE (450 3575);
FORCEPROP 1 LAST WATTAGE 1/16W
J 2
(400 3575);
DISPLAY 0.617021 (400 3575);
PAINT SKYBLUE (400 3575);
FORCEPROP 1 LASTPIN (325 3625) $PN 2
J 0
(287 3637);
DISPLAY 0.617021 (287 3637);
PAINT ORANGE (287 3637);
FORCEPROP 1 LASTPIN (125 3625) $PN 1
J 0
(137 3637);
DISPLAY 0.617021 (137 3637);
PAINT ORANGE (137 3637);
FORCEPROP 2 LAST SEC_TYPE 0402
J 0
(175 3825);
DISPLAY 1.021277 (175 3825);
PAINT ORANGE (175 3825);
DISPLAY INVISIBLE (175 3825);
FORCEPROP 2 LAST CDS_LIB mstr_discrete
J 0
(225 3625);
PAINT ORANGE (225 3625);
DISPLAY INVISIBLE (225 3625);
FORCEPROP 2 LAST BOM_COST PROC_SOCKET
J 0
(225 3625);
PAINT MONO (225 3625);
DISPLAY INVISIBLE (225 3625);
FORCEPROP 2 LAST SEC 1
J 0
(175 3825);
DISPLAY 0.680851 (175 3825);
PAINT MONO (175 3825);
DISPLAY INVISIBLE (175 3825);
FORCEPROP 2 LAST CDS_LOCATION R1G1
J 0
(175 3675);
DISPLAY 0.617021 (175 3675);
PAINT AQUA (175 3675);
DISPLAY INVISIBLE (175 3675);
FORCEPROP 1 LAST PATH I25
J 0
(175 3775);
DISPLAY 0.978723 (175 3775);
PAINT WHITE (175 3775);
DISPLAY INVISIBLE (175 3775);
FORCEPROP 0 LAST ROOM PROC
J 0
(150 3550);
DISPLAY 0.617021 (150 3550);
PAINT ORANGE (150 3550);
DISPLAY INVISIBLE (150 3550);
FORCEADD CAP_A..1
(0 3325);
FORCEPROP 1 LAST LOCATION C1G8
J 0
(50 3425);
DISPLAY 0.617021 (50 3425);
PAINT AQUA (50 3425);
FORCEPROP 1 LAST PART_NUMBER A36096-045
J 0
(50 3175);
DISPLAY 0.617021 (50 3175);
PAINT BLUE (50 3175);
FORCEPROP 1 LAST VALUE 0.01UF
J 0
(50 3375);
DISPLAY 0.617021 (50 3375);
PAINT SKYBLUE (50 3375);
FORCEPROP 1 LAST TOLERANCE 10%
J 0
(50 3275);
DISPLAY 0.617021 (50 3275);
PAINT SKYBLUE (50 3275);
FORCEPROP 1 LAST PACK_TYPE 0402V
J 0
(50 3125);
DISPLAY 0.617021 (50 3125);
PAINT SKYBLUE (50 3125);
FORCEPROP 1 LAST VOLTAGE 25V
J 0
(50 3325);
DISPLAY 0.617021 (50 3325);
PAINT SKYBLUE (50 3325);
FORCEPROP 1 LAST MATERIAL X7R
J 0
(50 3225);
DISPLAY 0.617021 (50 3225);
PAINT SKYBLUE (50 3225);
FORCEPROP 1 LASTPIN (0 3425) $PN 1
J 0
(10 3405);
DISPLAY 0.617021 (10 3405);
PAINT ORANGE (10 3405);
FORCEPROP 1 LASTPIN (0 3225) $PN 2
J 0
(10 3205);
DISPLAY 0.617021 (10 3205);
PAINT ORANGE (10 3205);
FORCEPROP 2 LAST CDS_LOCATION C1G8
J 0
(50 3425);
DISPLAY 0.617021 (50 3425);
PAINT AQUA (50 3425);
DISPLAY INVISIBLE (50 3425);
FORCEPROP 2 LAST BOM_COST PROC_SOCKET
J 0
(0 3325);
PAINT MONO (0 3325);
DISPLAY INVISIBLE (0 3325);
FORCEPROP 2 LAST CDS_LIB dev_discrete
J 0
(0 3325);
PAINT ORANGE (0 3325);
DISPLAY INVISIBLE (0 3325);
FORCEPROP 2 LAST CDS_SEC 1
J 0
(50 3475);
PAINT ORANGE (50 3475);
DISPLAY INVISIBLE (50 3475);
FORCEPROP 2 LAST SEC_TYPE 0402V
J 0
(50 3525);
DISPLAY 1.021277 (50 3525);
PAINT ORANGE (50 3525);
DISPLAY INVISIBLE (50 3525);
FORCEPROP 2 LAST SEC 1
J 0
(50 3525);
DISPLAY 0.680851 (50 3525);
PAINT MONO (50 3525);
DISPLAY INVISIBLE (50 3525);
FORCEPROP 1 LAST PATH I26
J 0
(50 3475);
DISPLAY 0.978723 (50 3475);
PAINT WHITE (50 3475);
DISPLAY INVISIBLE (50 3475);
FORCEPROP 0 LAST ROOM PROC
J 0
(50 3075);
DISPLAY 0.978723 (50 3075);
PAINT ORANGE (50 3075);
DISPLAY INVISIBLE (50 3075);
FORCEADD OFFPAGE..1
(-500 3625);
FORCEPROP 2 LAST $XR0 55 
J 0
(-721 3625);
DISPLAY 0.638298 (-721 3625);
PAINT MONO (-721 3625);
FORCEPROP 2 LAST CDS_LIB mstr_standard
J 0
(-500 3625);
PAINT MONO (-500 3625);
DISPLAY INVISIBLE (-500 3625);
FORCEPROP 1 LAST OFFPAGE TRUE
J 0
(-175 3500);
PAINT GREEN (-175 3500);
DISPLAY INVISIBLE (-175 3500);
FORCEPROP 1 LAST COMMENT_BODY TRUE
J 0
(-375 3525);
DISPLAY 1.170213 (-375 3525);
PAINT GREEN (-375 3525);
DISPLAY INVISIBLE (-375 3525);
FORCEPROP 2 LAST PATH I27
J 0
(-450 3700);
DISPLAY 1.021277 (-450 3700);
PAINT ORANGE (-450 3700);
DISPLAY INVISIBLE (-450 3700);
FORCEADD GND..1
(225 2975);
FORCEPROP 3 LASTPIN (225 3025) SIG_NAME GND\g
J 0
(235 3035);
DISPLAY 0.659574 (235 3035);
PAINT MONO (235 3035);
DISPLAY INVISIBLE (235 3035);
FORCEPROP 1 LAST VOLTAGE 0
J 0
(225 2975);
PAINT SKYBLUE (225 2975);
DISPLAY INVISIBLE (225 2975);
FORCEPROP 2 LAST CDS_LIB mstr_symbols
J 0
(225 2975);
PAINT MONO (225 2975);
DISPLAY INVISIBLE (225 2975);
FORCEPROP 1 LAST SIZE 1B
J 0
(300 2925);
DISPLAY 1.170213 (300 2925);
PAINT GREEN (300 2925);
DISPLAY INVISIBLE (300 2925);
FORCEPROP 1 LAST BODY_TYPE PLUMBING
J 0
(180 2932);
DISPLAY 0.340426 (180 2932);
PAINT GREEN (180 2932);
DISPLAY INVISIBLE (180 2932);
FORCEPROP 1 LAST PATH I28
J 0
(300 2975);
DISPLAY 0.872340 (300 2975);
PAINT AQUA (300 2975);
DISPLAY INVISIBLE (300 2975);
FORCEPROP 1 LAST HDL_POWER GND
J 0
(225 3125);
DISPLAY 1.170213 (225 3125);
PAINT GREEN (225 3125);
DISPLAY INVISIBLE (225 3125);
FORCEADD RES..1
(225 1950);
FORCEPROP 1 LAST LOCATION R9L8
J 0
(200 2025);
DISPLAY 0.617021 (200 2025);
PAINT AQUA (200 2025);
FORCEPROP 1 LAST PART_NUMBER G21796-274
J 0
(100 1800);
DISPLAY 0.617021 (100 1800);
PAINT BLUE (100 1800);
FORCEPROP 1 LAST VALUE 2
J 2
(150 1900);
DISPLAY 0.617021 (150 1900);
PAINT SKYBLUE (150 1900);
FORCEPROP 1 LAST TOLERANCE 1.0%
J 0
(325 1850);
DISPLAY 0.617021 (325 1850);
PAINT SKYBLUE (325 1850);
FORCEPROP 1 LAST PACK_TYPE 0402
J 0
(100 1850);
DISPLAY 0.617021 (100 1850);
PAINT SKYBLUE (100 1850);
FORCEPROP 1 LAST MATERIAL CHIP
J 0
(450 1900);
DISPLAY 0.617021 (450 1900);
PAINT SKYBLUE (450 1900);
FORCEPROP 1 LAST WATTAGE 1/16W
J 2
(400 1900);
DISPLAY 0.617021 (400 1900);
PAINT SKYBLUE (400 1900);
FORCEPROP 1 LASTPIN (325 1950) $PN 2
J 0
(287 1962);
DISPLAY 0.617021 (287 1962);
PAINT MONO (287 1962);
FORCEPROP 1 LASTPIN (125 1950) $PN 1
J 0
(137 1962);
DISPLAY 0.617021 (137 1962);
PAINT MONO (137 1962);
FORCEPROP 2 LAST BOM_COST PROC_SOCKET
J 0
(225 1950);
PAINT MONO (225 1950);
DISPLAY INVISIBLE (225 1950);
FORCEPROP 2 LAST SEC_TYPE 0402
J 0
(175 2150);
PAINT MONO (175 2150);
DISPLAY INVISIBLE (175 2150);
FORCEPROP 2 LAST CDS_LIB mstr_discrete
J 0
(225 1950);
PAINT ORANGE (225 1950);
DISPLAY INVISIBLE (225 1950);
FORCEPROP 2 LAST SEC 1
J 0
(175 2150);
DISPLAY 0.936170 (175 2150);
PAINT MONO (175 2150);
DISPLAY INVISIBLE (175 2150);
FORCEPROP 2 LAST CDS_LOCATION R9L8
J 0
(200 2025);
DISPLAY 0.617021 (200 2025);
PAINT AQUA (200 2025);
DISPLAY INVISIBLE (200 2025);
FORCEPROP 1 LAST PATH I29
J 0
(175 2100);
DISPLAY 0.978723 (175 2100);
PAINT WHITE (175 2100);
DISPLAY INVISIBLE (175 2100);
FORCEPROP 0 LAST ROOM PROC
J 0
(150 1875);
DISPLAY 0.617021 (150 1875);
PAINT ORANGE (150 1875);
DISPLAY INVISIBLE (150 1875);
FORCEADD OFFPAGE..2
(-1475 1950);
FORCEPROP 2 LAST $XR1 84 
J 0
(-1196 1950);
DISPLAY 0.638298 (-1196 1950);
PAINT MONO (-1196 1950);
FORCEPROP 2 LAST $XR0 83 
J 0
(-1286 1950);
DISPLAY 0.638298 (-1286 1950);
PAINT MONO (-1286 1950);
FORCEPROP 2 LAST CDS_LIB mstr_standard
J 0
(-1475 1950);
PAINT MONO (-1475 1950);
DISPLAY INVISIBLE (-1475 1950);
FORCEPROP 1 LAST OFFPAGE TRUE
J 0
(-1150 1825);
PAINT GREEN (-1150 1825);
DISPLAY INVISIBLE (-1150 1825);
FORCEPROP 1 LAST COMMENT_BODY TRUE
J 0
(-1520 1855);
DISPLAY 1.170213 (-1520 1855);
PAINT GREEN (-1520 1855);
DISPLAY INVISIBLE (-1520 1855);
FORCEPROP 2 LAST PATH I3
J 0
(-1300 2025);
DISPLAY 1.021277 (-1300 2025);
PAINT ORANGE (-1300 2025);
DISPLAY INVISIBLE (-1300 2025);
FORCEADD CAP_A..1
(0 1650);
FORCEPROP 1 LAST LOCATION C9L8
J 0
(50 1750);
DISPLAY 0.617021 (50 1750);
PAINT AQUA (50 1750);
FORCEPROP 1 LAST PART_NUMBER A36096-045
J 0
(50 1500);
DISPLAY 0.617021 (50 1500);
PAINT BLUE (50 1500);
FORCEPROP 1 LAST VALUE 0.01UF
J 0
(50 1700);
DISPLAY 0.617021 (50 1700);
PAINT SKYBLUE (50 1700);
FORCEPROP 1 LAST TOLERANCE 10%
J 0
(50 1600);
DISPLAY 0.617021 (50 1600);
PAINT SKYBLUE (50 1600);
FORCEPROP 1 LAST PACK_TYPE 0402V
J 0
(50 1450);
DISPLAY 0.617021 (50 1450);
PAINT SKYBLUE (50 1450);
FORCEPROP 1 LAST VOLTAGE 25V
J 0
(50 1650);
DISPLAY 0.617021 (50 1650);
PAINT SKYBLUE (50 1650);
FORCEPROP 1 LAST MATERIAL X7R
J 0
(50 1550);
DISPLAY 0.617021 (50 1550);
PAINT SKYBLUE (50 1550);
FORCEPROP 1 LASTPIN (0 1750) $PN 1
J 0
(10 1730);
DISPLAY 0.617021 (10 1730);
PAINT ORANGE (10 1730);
FORCEPROP 1 LASTPIN (0 1550) $PN 2
J 0
(10 1530);
DISPLAY 0.617021 (10 1530);
PAINT ORANGE (10 1530);
FORCEPROP 2 LAST CDS_LOCATION C9L8
J 0
(50 1750);
DISPLAY 0.617021 (50 1750);
PAINT AQUA (50 1750);
DISPLAY INVISIBLE (50 1750);
FORCEPROP 2 LAST BOM_COST SM_CONTROLLER
J 0
(0 1650);
PAINT MONO (0 1650);
DISPLAY INVISIBLE (0 1650);
FORCEPROP 2 LAST CDS_LIB dev_discrete
J 0
(0 1650);
PAINT ORANGE (0 1650);
DISPLAY INVISIBLE (0 1650);
FORCEPROP 2 LAST CDS_SEC 1
J 0
(50 1800);
PAINT ORANGE (50 1800);
DISPLAY INVISIBLE (50 1800);
FORCEPROP 2 LAST SEC_TYPE 0402V
J 0
(50 1850);
DISPLAY 1.021277 (50 1850);
PAINT ORANGE (50 1850);
DISPLAY INVISIBLE (50 1850);
FORCEPROP 2 LAST SEC 1
J 0
(50 1850);
DISPLAY 0.680851 (50 1850);
PAINT MONO (50 1850);
DISPLAY INVISIBLE (50 1850);
FORCEPROP 1 LAST PATH I30
J 0
(50 1800);
DISPLAY 0.978723 (50 1800);
PAINT WHITE (50 1800);
DISPLAY INVISIBLE (50 1800);
FORCEPROP 0 LAST ROOM MEM
J 0
(50 1400);
DISPLAY 0.978723 (50 1400);
PAINT ORANGE (50 1400);
DISPLAY INVISIBLE (50 1400);
FORCEADD GND..1
(225 1300);
FORCEPROP 3 LASTPIN (225 1350) SIG_NAME GND\g
J 0
(235 1360);
DISPLAY 0.659574 (235 1360);
PAINT MONO (235 1360);
DISPLAY INVISIBLE (235 1360);
FORCEPROP 1 LAST VOLTAGE 0
J 0
(225 1300);
PAINT SKYBLUE (225 1300);
DISPLAY INVISIBLE (225 1300);
FORCEPROP 2 LAST CDS_LIB mstr_symbols
J 0
(225 1300);
PAINT MONO (225 1300);
DISPLAY INVISIBLE (225 1300);
FORCEPROP 1 LAST SIZE 1B
J 0
(300 1250);
DISPLAY 1.170213 (300 1250);
PAINT GREEN (300 1250);
DISPLAY INVISIBLE (300 1250);
FORCEPROP 1 LAST BODY_TYPE PLUMBING
J 0
(180 1257);
DISPLAY 0.340426 (180 1257);
PAINT GREEN (180 1257);
DISPLAY INVISIBLE (180 1257);
FORCEPROP 1 LAST PATH I31
J 0
(300 1300);
DISPLAY 0.872340 (300 1300);
PAINT AQUA (300 1300);
DISPLAY INVISIBLE (300 1300);
FORCEPROP 1 LAST HDL_POWER GND
J 0
(225 1450);
DISPLAY 1.170213 (225 1450);
PAINT GREEN (225 1450);
DISPLAY INVISIBLE (225 1450);
FORCEADD OFFPAGE..1
(-500 1950);
FORCEPROP 2 LAST $XR0 55 
J 0
(-721 1950);
DISPLAY 0.638298 (-721 1950);
PAINT MONO (-721 1950);
FORCEPROP 2 LAST CDS_LIB mstr_standard
J 0
(-500 1950);
PAINT MONO (-500 1950);
DISPLAY INVISIBLE (-500 1950);
FORCEPROP 1 LAST OFFPAGE TRUE
J 0
(-175 1825);
PAINT GREEN (-175 1825);
DISPLAY INVISIBLE (-175 1825);
FORCEPROP 1 LAST COMMENT_BODY TRUE
J 0
(-375 1850);
DISPLAY 1.170213 (-375 1850);
PAINT GREEN (-375 1850);
DISPLAY INVISIBLE (-375 1850);
FORCEPROP 2 LAST PATH I32
J 0
(-450 2025);
DISPLAY 1.021277 (-450 2025);
PAINT ORANGE (-450 2025);
DISPLAY INVISIBLE (-450 2025);
FORCEADD PVDDQ_GHJ..1
(2900 4200);
FORCEPROP 3 LASTPIN (2900 4150) SIG_NAME PVDDQ_GHJ\g
J 0
(2910 4160);
DISPLAY 0.659574 (2910 4160);
PAINT MONO (2910 4160);
DISPLAY INVISIBLE (2910 4160);
FORCEPROP 1 LAST VOLTAGE 1.2V
J 0
(2855 4157);
DISPLAY 0.340426 (2855 4157);
PAINT SKYBLUE (2855 4157);
DISPLAY INVISIBLE (2855 4157);
FORCEPROP 2 LAST CDS_LIB mstr_symbols
J 0
(2900 4200);
PAINT ORANGE (2900 4200);
DISPLAY INVISIBLE (2900 4200);
FORCEPROP 1 LAST BODY_TYPE PLUMBING
J 0
(2855 4157);
DISPLAY 0.340426 (2855 4157);
PAINT GREEN (2855 4157);
DISPLAY INVISIBLE (2855 4157);
FORCEPROP 1 LAST PATH I33
J 0
(2950 4225);
DISPLAY 0.872340 (2950 4225);
PAINT AQUA (2950 4225);
DISPLAY INVISIBLE (2950 4225);
FORCEPROP 1 LAST HDL_POWER PVDDQ_GHJ
J 1
(2900 4250);
DISPLAY 0.872340 (2900 4250);
PAINT GREEN (2900 4250);
DISPLAY INVISIBLE (2900 4250);
FORCEADD OFFPAGE..2
(3325 3625);
FORCEPROP 2 LAST $XR1 82 
J 0
(3604 3625);
DISPLAY 0.638298 (3604 3625);
PAINT MONO (3604 3625);
FORCEPROP 2 LAST $XR0 81 
J 0
(3514 3625);
DISPLAY 0.638298 (3514 3625);
PAINT MONO (3514 3625);
FORCEPROP 2 LAST CDS_LIB mstr_standard
J 0
(3325 3625);
PAINT MONO (3325 3625);
DISPLAY INVISIBLE (3325 3625);
FORCEPROP 1 LAST OFFPAGE TRUE
J 0
(3650 3500);
PAINT GREEN (3650 3500);
DISPLAY INVISIBLE (3650 3500);
FORCEPROP 1 LAST COMMENT_BODY TRUE
J 0
(3280 3530);
DISPLAY 1.170213 (3280 3530);
PAINT GREEN (3280 3530);
DISPLAY INVISIBLE (3280 3530);
FORCEPROP 2 LAST PATH I34
J 0
(3500 3700);
DISPLAY 1.021277 (3500 3700);
PAINT ORANGE (3500 3700);
DISPLAY INVISIBLE (3500 3700);
FORCEADD RES..2
R 2
(2900 3950);
FORCEPROP 1 LAST LOCATION R1G15
J 2
(2855 4075);
DISPLAY 0.617021 (2855 4075);
PAINT AQUA (2855 4075);
FORCEPROP 1 LAST PART_NUMBER G21796-026
J 2
(2860 3825);
DISPLAY 0.617021 (2860 3825);
PAINT BLUE (2860 3825);
FORCEPROP 1 LAST VALUE 1.00K
J 2
(2855 4025);
DISPLAY 0.617021 (2855 4025);
PAINT SKYBLUE (2855 4025);
FORCEPROP 1 LAST TOLERANCE 1%
J 2
(2855 3975);
DISPLAY 0.617021 (2855 3975);
PAINT SKYBLUE (2855 3975);
FORCEPROP 1 LAST PACK_TYPE 0402
J 2
(2860 3775);
DISPLAY 0.617021 (2860 3775);
PAINT SKYBLUE (2860 3775);
FORCEPROP 1 LAST MATERIAL CHIP
J 2
(2860 3875);
DISPLAY 0.617021 (2860 3875);
PAINT SKYBLUE (2860 3875);
FORCEPROP 1 LAST WATTAGE 1/16W
J 2
(2860 3925);
DISPLAY 0.617021 (2860 3925);
PAINT SKYBLUE (2860 3925);
FORCEPROP 1 LASTPIN (2900 3850) $PN 2
J 2
(2895 3860);
DISPLAY 0.617021 (2895 3860);
PAINT ORANGE (2895 3860);
FORCEPROP 1 LASTPIN (2900 4050) $PN 1
J 2
(2895 4012);
DISPLAY 0.617021 (2895 4012);
PAINT ORANGE (2895 4012);
FORCEPROP 2 LAST SEC_TYPE 0402
J 0
(2850 4175);
DISPLAY 1.021277 (2850 4175);
PAINT ORANGE (2850 4175);
DISPLAY INVISIBLE (2850 4175);
FORCEPROP 2 LAST BOM_COST SM_CONTROLLER
J 2
(2900 3950);
PAINT MONO (2900 3950);
DISPLAY INVISIBLE (2900 3950);
FORCEPROP 2 LAST CDS_LIB mstr_discrete
J 0
(2900 3950);
PAINT ORANGE (2900 3950);
DISPLAY INVISIBLE (2900 3950);
FORCEPROP 2 LAST SEC 1
J 0
(2850 4175);
DISPLAY 0.680851 (2850 4175);
PAINT MONO (2850 4175);
DISPLAY INVISIBLE (2850 4175);
FORCEPROP 2 LAST CDS_LOCATION R1G15
J 2
(2855 4075);
DISPLAY 0.617021 (2855 4075);
PAINT AQUA (2855 4075);
DISPLAY INVISIBLE (2855 4075);
FORCEPROP 1 LAST PATH I35
J 2
(2850 4125);
DISPLAY 0.978723 (2850 4125);
PAINT WHITE (2850 4125);
DISPLAY INVISIBLE (2850 4125);
FORCEPROP 2 LAST ROOM MEM
J 2
(2850 4125);
PAINT PEACH (2850 4125);
DISPLAY INVISIBLE (2850 4125);
FORCEADD RES..2
R 2
(2975 3300);
FORCEPROP 1 LAST LOCATION R1G17
J 2
(2930 3425);
DISPLAY 0.617021 (2930 3425);
PAINT AQUA (2930 3425);
FORCEPROP 1 LAST PART_NUMBER G21796-026
J 2
(2935 3175);
DISPLAY 0.617021 (2935 3175);
PAINT BLUE (2935 3175);
FORCEPROP 1 LAST VALUE 1.00K
J 2
(2930 3375);
DISPLAY 0.617021 (2930 3375);
PAINT SKYBLUE (2930 3375);
FORCEPROP 1 LAST TOLERANCE 1%
J 2
(2930 3325);
DISPLAY 0.617021 (2930 3325);
PAINT SKYBLUE (2930 3325);
FORCEPROP 1 LAST PACK_TYPE 0402
J 2
(2935 3125);
DISPLAY 0.617021 (2935 3125);
PAINT SKYBLUE (2935 3125);
FORCEPROP 1 LAST MATERIAL CHIP
J 2
(2935 3225);
DISPLAY 0.617021 (2935 3225);
PAINT SKYBLUE (2935 3225);
FORCEPROP 1 LAST WATTAGE 1/16W
J 2
(2935 3275);
DISPLAY 0.617021 (2935 3275);
PAINT SKYBLUE (2935 3275);
FORCEPROP 1 LASTPIN (2975 3200) $PN 2
J 2
(2970 3210);
DISPLAY 0.617021 (2970 3210);
PAINT ORANGE (2970 3210);
FORCEPROP 1 LASTPIN (2975 3400) $PN 1
J 2
(2970 3362);
DISPLAY 0.617021 (2970 3362);
PAINT ORANGE (2970 3362);
FORCEPROP 2 LAST SEC_TYPE 0402
J 0
(2925 3525);
DISPLAY 1.021277 (2925 3525);
PAINT ORANGE (2925 3525);
DISPLAY INVISIBLE (2925 3525);
FORCEPROP 2 LAST BOM_COST SM_CONTROLLER
J 2
(2975 3300);
PAINT MONO (2975 3300);
DISPLAY INVISIBLE (2975 3300);
FORCEPROP 2 LAST CDS_LIB mstr_discrete
J 0
(2975 3300);
PAINT ORANGE (2975 3300);
DISPLAY INVISIBLE (2975 3300);
FORCEPROP 2 LAST SEC 1
J 0
(2925 3525);
DISPLAY 0.680851 (2925 3525);
PAINT MONO (2925 3525);
DISPLAY INVISIBLE (2925 3525);
FORCEPROP 2 LAST CDS_LOCATION R1G17
J 2
(2930 3425);
DISPLAY 0.617021 (2930 3425);
PAINT AQUA (2930 3425);
DISPLAY INVISIBLE (2930 3425);
FORCEPROP 1 LAST PATH I36
J 2
(2925 3475);
DISPLAY 0.978723 (2925 3475);
PAINT WHITE (2925 3475);
DISPLAY INVISIBLE (2925 3475);
FORCEPROP 2 LAST ROOM MEM
J 2
(2925 3475);
PAINT PEACH (2925 3475);
DISPLAY INVISIBLE (2925 3475);
FORCEADD PVDDQ_KLM..1
(2900 2525);
FORCEPROP 3 LASTPIN (2900 2475) SIG_NAME PVDDQ_KLM\g
J 0
(2910 2485);
DISPLAY 0.659574 (2910 2485);
PAINT MONO (2910 2485);
DISPLAY INVISIBLE (2910 2485);
FORCEPROP 1 LAST VOLTAGE 1.2V
J 0
(2855 2482);
DISPLAY 0.340426 (2855 2482);
PAINT SKYBLUE (2855 2482);
DISPLAY INVISIBLE (2855 2482);
FORCEPROP 2 LAST CDS_LIB mstr_symbols
J 0
(2900 2525);
PAINT ORANGE (2900 2525);
DISPLAY INVISIBLE (2900 2525);
FORCEPROP 1 LAST BODY_TYPE PLUMBING
J 0
(2855 2482);
DISPLAY 0.340426 (2855 2482);
PAINT GREEN (2855 2482);
DISPLAY INVISIBLE (2855 2482);
FORCEPROP 1 LAST PATH I37
J 0
(2950 2550);
DISPLAY 0.872340 (2950 2550);
PAINT AQUA (2950 2550);
DISPLAY INVISIBLE (2950 2550);
FORCEPROP 1 LAST HDL_POWER PVDDQ_KLM
J 1
(2900 2575);
DISPLAY 0.872340 (2900 2575);
PAINT GREEN (2900 2575);
DISPLAY INVISIBLE (2900 2575);
FORCEADD RES..2
R 2
(2900 2275);
FORCEPROP 1 LAST LOCATION R9L2
J 2
(2855 2400);
DISPLAY 0.617021 (2855 2400);
PAINT AQUA (2855 2400);
FORCEPROP 1 LAST PART_NUMBER G21796-026
J 2
(2860 2150);
DISPLAY 0.617021 (2860 2150);
PAINT BLUE (2860 2150);
FORCEPROP 1 LAST VALUE 1.00K
J 2
(2855 2350);
DISPLAY 0.617021 (2855 2350);
PAINT SKYBLUE (2855 2350);
FORCEPROP 1 LAST TOLERANCE 1%
J 2
(2855 2300);
DISPLAY 0.617021 (2855 2300);
PAINT SKYBLUE (2855 2300);
FORCEPROP 1 LAST PACK_TYPE 0402
J 2
(2860 2100);
DISPLAY 0.617021 (2860 2100);
PAINT SKYBLUE (2860 2100);
FORCEPROP 1 LAST MATERIAL CHIP
J 2
(2860 2200);
DISPLAY 0.617021 (2860 2200);
PAINT SKYBLUE (2860 2200);
FORCEPROP 1 LAST WATTAGE 1/16W
J 2
(2860 2250);
DISPLAY 0.617021 (2860 2250);
PAINT SKYBLUE (2860 2250);
FORCEPROP 1 LASTPIN (2900 2175) $PN 2
J 2
(2895 2185);
DISPLAY 0.617021 (2895 2185);
PAINT ORANGE (2895 2185);
FORCEPROP 1 LASTPIN (2900 2375) $PN 1
J 2
(2895 2337);
DISPLAY 0.617021 (2895 2337);
PAINT ORANGE (2895 2337);
FORCEPROP 2 LAST SEC_TYPE 0402
J 0
(2850 2500);
DISPLAY 1.021277 (2850 2500);
PAINT ORANGE (2850 2500);
DISPLAY INVISIBLE (2850 2500);
FORCEPROP 2 LAST CDS_LIB mstr_discrete
J 0
(2900 2275);
PAINT ORANGE (2900 2275);
DISPLAY INVISIBLE (2900 2275);
FORCEPROP 2 LAST BOM_COST SM_CONTROLLER
J 2
(2900 2275);
PAINT MONO (2900 2275);
DISPLAY INVISIBLE (2900 2275);
FORCEPROP 2 LAST SEC 1
J 0
(2850 2500);
DISPLAY 0.680851 (2850 2500);
PAINT MONO (2850 2500);
DISPLAY INVISIBLE (2850 2500);
FORCEPROP 2 LAST CDS_LOCATION R9L2
J 2
(2855 2400);
DISPLAY 0.617021 (2855 2400);
PAINT AQUA (2855 2400);
DISPLAY INVISIBLE (2855 2400);
FORCEPROP 1 LAST PATH I38
J 2
(2850 2450);
DISPLAY 0.978723 (2850 2450);
PAINT WHITE (2850 2450);
DISPLAY INVISIBLE (2850 2450);
FORCEPROP 2 LAST ROOM MEM
J 2
(2850 2450);
PAINT PEACH (2850 2450);
DISPLAY INVISIBLE (2850 2450);
FORCEADD OFFPAGE..2
(3325 1950);
FORCEPROP 2 LAST $XR1 88 
J 0
(3604 1950);
DISPLAY 0.638298 (3604 1950);
PAINT MONO (3604 1950);
FORCEPROP 2 LAST $XR0 87 
J 0
(3514 1950);
DISPLAY 0.638298 (3514 1950);
PAINT MONO (3514 1950);
FORCEPROP 2 LAST CDS_LIB mstr_standard
J 0
(3325 1950);
PAINT MONO (3325 1950);
DISPLAY INVISIBLE (3325 1950);
FORCEPROP 1 LAST OFFPAGE TRUE
J 0
(3650 1825);
PAINT GREEN (3650 1825);
DISPLAY INVISIBLE (3650 1825);
FORCEPROP 1 LAST COMMENT_BODY TRUE
J 0
(3280 1855);
DISPLAY 1.170213 (3280 1855);
PAINT GREEN (3280 1855);
DISPLAY INVISIBLE (3280 1855);
FORCEPROP 2 LAST PATH I39
J 0
(3500 2025);
DISPLAY 1.021277 (3500 2025);
PAINT ORANGE (3500 2025);
DISPLAY INVISIBLE (3500 2025);
FORCEADD RES..2
R 2
(-1825 1625);
FORCEPROP 1 LAST LOCATION R9L11
J 2
(-1870 1750);
DISPLAY 0.617021 (-1870 1750);
PAINT AQUA (-1870 1750);
FORCEPROP 1 LAST PART_NUMBER G21796-026
J 2
(-1865 1500);
DISPLAY 0.617021 (-1865 1500);
PAINT BLUE (-1865 1500);
FORCEPROP 1 LAST VALUE 1.00K
J 2
(-1870 1700);
DISPLAY 0.617021 (-1870 1700);
PAINT SKYBLUE (-1870 1700);
FORCEPROP 1 LAST TOLERANCE 1%
J 2
(-1870 1650);
DISPLAY 0.617021 (-1870 1650);
PAINT SKYBLUE (-1870 1650);
FORCEPROP 1 LAST PACK_TYPE 0402
J 2
(-1865 1450);
DISPLAY 0.617021 (-1865 1450);
PAINT SKYBLUE (-1865 1450);
FORCEPROP 1 LAST MATERIAL CHIP
J 2
(-1865 1550);
DISPLAY 0.617021 (-1865 1550);
PAINT SKYBLUE (-1865 1550);
FORCEPROP 1 LAST WATTAGE 1/16W
J 2
(-1865 1600);
DISPLAY 0.617021 (-1865 1600);
PAINT SKYBLUE (-1865 1600);
FORCEPROP 1 LASTPIN (-1825 1525) $PN 2
J 2
(-1830 1535);
DISPLAY 0.617021 (-1830 1535);
PAINT ORANGE (-1830 1535);
FORCEPROP 1 LASTPIN (-1825 1725) $PN 1
J 2
(-1830 1687);
DISPLAY 0.617021 (-1830 1687);
PAINT ORANGE (-1830 1687);
FORCEPROP 2 LAST CDS_LIB mstr_discrete
J 0
(-1825 1625);
PAINT ORANGE (-1825 1625);
DISPLAY INVISIBLE (-1825 1625);
FORCEPROP 2 LAST BOM_COST PROC_SOCKET
J 2
(-1825 1625);
PAINT MONO (-1825 1625);
DISPLAY INVISIBLE (-1825 1625);
FORCEPROP 2 LAST SEC_TYPE 0402
J 0
(-1875 1850);
DISPLAY 1.021277 (-1875 1850);
PAINT ORANGE (-1875 1850);
DISPLAY INVISIBLE (-1875 1850);
FORCEPROP 2 LAST SEC 1
J 0
(-1875 1850);
DISPLAY 0.680851 (-1875 1850);
PAINT MONO (-1875 1850);
DISPLAY INVISIBLE (-1875 1850);
FORCEPROP 2 LAST CDS_LOCATION R9L11
J 2
(-1870 1750);
DISPLAY 0.617021 (-1870 1750);
PAINT AQUA (-1870 1750);
DISPLAY INVISIBLE (-1870 1750);
FORCEPROP 1 LAST PATH I4
J 2
(-1875 1800);
DISPLAY 0.978723 (-1875 1800);
PAINT WHITE (-1875 1800);
DISPLAY INVISIBLE (-1875 1800);
FORCEPROP 2 LAST ROOM PROC
J 2
(-1875 1800);
PAINT PEACH (-1875 1800);
DISPLAY INVISIBLE (-1875 1800);
FORCEADD RES..2
R 2
(2975 1625);
FORCEPROP 1 LAST LOCATION R9L1
J 2
(2930 1750);
DISPLAY 0.617021 (2930 1750);
PAINT AQUA (2930 1750);
FORCEPROP 1 LAST PART_NUMBER G21796-026
J 2
(2935 1500);
DISPLAY 0.617021 (2935 1500);
PAINT BLUE (2935 1500);
FORCEPROP 1 LAST TOLERANCE 1%
J 2
(2930 1650);
DISPLAY 0.617021 (2930 1650);
PAINT SKYBLUE (2930 1650);
FORCEPROP 1 LAST PACK_TYPE 0402
J 2
(2935 1450);
DISPLAY 0.617021 (2935 1450);
PAINT SKYBLUE (2935 1450);
FORCEPROP 1 LAST MATERIAL CHIP
J 2
(2935 1550);
DISPLAY 0.617021 (2935 1550);
PAINT SKYBLUE (2935 1550);
FORCEPROP 1 LAST WATTAGE 1/16W
J 2
(2935 1600);
DISPLAY 0.617021 (2935 1600);
PAINT SKYBLUE (2935 1600);
FORCEPROP 1 LASTPIN (2975 1525) $PN 2
J 2
(2970 1535);
DISPLAY 0.617021 (2970 1535);
PAINT ORANGE (2970 1535);
FORCEPROP 1 LASTPIN (2975 1725) $PN 1
J 2
(2970 1687);
DISPLAY 0.617021 (2970 1687);
PAINT ORANGE (2970 1687);
FORCEPROP 1 LAST VALUE 1.00K
J 2
(2930 1700);
DISPLAY 0.617021 (2930 1700);
PAINT SKYBLUE (2930 1700);
FORCEPROP 2 LAST SEC_TYPE 0402
J 0
(2925 1850);
DISPLAY 1.021277 (2925 1850);
PAINT ORANGE (2925 1850);
DISPLAY INVISIBLE (2925 1850);
FORCEPROP 2 LAST BOM_COST PROC_SOCKET
J 2
(2975 1625);
PAINT MONO (2975 1625);
DISPLAY INVISIBLE (2975 1625);
FORCEPROP 2 LAST CDS_LIB mstr_discrete
J 0
(2975 1625);
PAINT ORANGE (2975 1625);
DISPLAY INVISIBLE (2975 1625);
FORCEPROP 2 LAST SEC 1
J 0
(2925 1850);
DISPLAY 0.680851 (2925 1850);
PAINT MONO (2925 1850);
DISPLAY INVISIBLE (2925 1850);
FORCEPROP 2 LAST CDS_LOCATION R9L1
J 2
(2930 1750);
DISPLAY 0.617021 (2930 1750);
PAINT AQUA (2930 1750);
DISPLAY INVISIBLE (2930 1750);
FORCEPROP 1 LAST PATH I40
J 2
(2925 1800);
DISPLAY 0.978723 (2925 1800);
PAINT WHITE (2925 1800);
DISPLAY INVISIBLE (2925 1800);
FORCEPROP 2 LAST ROOM PROC
J 2
(2925 1800);
PAINT PEACH (2925 1800);
DISPLAY INVISIBLE (2925 1800);
FORCEADD RES..1
(2675 3625);
FORCEPROP 1 LAST LOCATION R1G14
J 0
(2625 3675);
DISPLAY 0.617021 (2625 3675);
PAINT AQUA (2625 3675);
FORCEPROP 1 LAST PART_NUMBER G21796-274
J 0
(2550 3475);
DISPLAY 0.617021 (2550 3475);
PAINT BLUE (2550 3475);
FORCEPROP 1 LAST VALUE 2
J 2
(2600 3575);
DISPLAY 0.617021 (2600 3575);
PAINT SKYBLUE (2600 3575);
FORCEPROP 1 LAST TOLERANCE 1.0%
J 0
(2775 3525);
DISPLAY 0.617021 (2775 3525);
PAINT SKYBLUE (2775 3525);
FORCEPROP 1 LAST PACK_TYPE 0402
J 0
(2550 3525);
DISPLAY 0.617021 (2550 3525);
PAINT SKYBLUE (2550 3525);
FORCEPROP 1 LAST MATERIAL CHIP
J 0
(2900 3575);
DISPLAY 0.617021 (2900 3575);
PAINT SKYBLUE (2900 3575);
FORCEPROP 1 LAST WATTAGE 1/16W
J 2
(2850 3575);
DISPLAY 0.617021 (2850 3575);
PAINT SKYBLUE (2850 3575);
FORCEPROP 1 LASTPIN (2775 3625) $PN 2
J 0
(2737 3637);
DISPLAY 0.617021 (2737 3637);
PAINT ORANGE (2737 3637);
FORCEPROP 1 LASTPIN (2575 3625) $PN 1
J 0
(2587 3637);
DISPLAY 0.617021 (2587 3637);
PAINT ORANGE (2587 3637);
FORCEPROP 2 LAST SEC_TYPE 0402
J 0
(2625 3825);
DISPLAY 1.021277 (2625 3825);
PAINT ORANGE (2625 3825);
DISPLAY INVISIBLE (2625 3825);
FORCEPROP 2 LAST CDS_LIB mstr_discrete
J 0
(2675 3625);
PAINT ORANGE (2675 3625);
DISPLAY INVISIBLE (2675 3625);
FORCEPROP 2 LAST BOM_COST PROC_SOCKET
J 0
(2675 3625);
PAINT MONO (2675 3625);
DISPLAY INVISIBLE (2675 3625);
FORCEPROP 2 LAST SEC 1
J 0
(2625 3825);
DISPLAY 0.680851 (2625 3825);
PAINT MONO (2625 3825);
DISPLAY INVISIBLE (2625 3825);
FORCEPROP 2 LAST CDS_LOCATION R1G14
J 0
(2625 3675);
DISPLAY 0.617021 (2625 3675);
PAINT AQUA (2625 3675);
DISPLAY INVISIBLE (2625 3675);
FORCEPROP 1 LAST PATH I41
J 0
(2625 3775);
DISPLAY 0.978723 (2625 3775);
PAINT WHITE (2625 3775);
DISPLAY INVISIBLE (2625 3775);
FORCEPROP 0 LAST ROOM PROC
J 0
(2600 3550);
DISPLAY 0.617021 (2600 3550);
PAINT ORANGE (2600 3550);
DISPLAY INVISIBLE (2600 3550);
FORCEADD CAP_A..1
(2450 3325);
FORCEPROP 1 LAST LOCATION C1G18
J 0
(2500 3425);
DISPLAY 0.617021 (2500 3425);
PAINT AQUA (2500 3425);
FORCEPROP 1 LAST PART_NUMBER A36096-045
J 0
(2500 3175);
DISPLAY 0.617021 (2500 3175);
PAINT BLUE (2500 3175);
FORCEPROP 1 LAST VALUE 0.01UF
J 0
(2500 3375);
DISPLAY 0.617021 (2500 3375);
PAINT SKYBLUE (2500 3375);
FORCEPROP 1 LAST TOLERANCE 10%
J 0
(2500 3275);
DISPLAY 0.617021 (2500 3275);
PAINT SKYBLUE (2500 3275);
FORCEPROP 1 LAST PACK_TYPE 0402V
J 0
(2500 3125);
DISPLAY 0.617021 (2500 3125);
PAINT SKYBLUE (2500 3125);
FORCEPROP 1 LAST VOLTAGE 25V
J 0
(2500 3325);
DISPLAY 0.617021 (2500 3325);
PAINT SKYBLUE (2500 3325);
FORCEPROP 1 LAST MATERIAL X7R
J 0
(2500 3225);
DISPLAY 0.617021 (2500 3225);
PAINT SKYBLUE (2500 3225);
FORCEPROP 1 LASTPIN (2450 3425) $PN 1
J 0
(2460 3405);
DISPLAY 0.617021 (2460 3405);
PAINT ORANGE (2460 3405);
FORCEPROP 1 LASTPIN (2450 3225) $PN 2
J 0
(2460 3205);
DISPLAY 0.617021 (2460 3205);
PAINT ORANGE (2460 3205);
FORCEPROP 2 LAST CDS_LOCATION C1G18
J 0
(2500 3425);
DISPLAY 0.617021 (2500 3425);
PAINT AQUA (2500 3425);
DISPLAY INVISIBLE (2500 3425);
FORCEPROP 2 LAST BOM_COST PROC_SOCKET
J 0
(2450 3325);
PAINT MONO (2450 3325);
DISPLAY INVISIBLE (2450 3325);
FORCEPROP 2 LAST CDS_LIB dev_discrete
J 0
(2450 3325);
PAINT ORANGE (2450 3325);
DISPLAY INVISIBLE (2450 3325);
FORCEPROP 2 LAST CDS_SEC 1
J 0
(2500 3475);
PAINT ORANGE (2500 3475);
DISPLAY INVISIBLE (2500 3475);
FORCEPROP 2 LAST SEC_TYPE 0402V
J 0
(2500 3525);
DISPLAY 1.021277 (2500 3525);
PAINT ORANGE (2500 3525);
DISPLAY INVISIBLE (2500 3525);
FORCEPROP 2 LAST SEC 1
J 0
(2500 3525);
DISPLAY 0.680851 (2500 3525);
PAINT MONO (2500 3525);
DISPLAY INVISIBLE (2500 3525);
FORCEPROP 1 LAST PATH I42
J 0
(2500 3475);
DISPLAY 0.978723 (2500 3475);
PAINT WHITE (2500 3475);
DISPLAY INVISIBLE (2500 3475);
FORCEPROP 0 LAST ROOM PROC
J 0
(2500 3075);
DISPLAY 0.978723 (2500 3075);
PAINT ORANGE (2500 3075);
DISPLAY INVISIBLE (2500 3075);
FORCEADD OFFPAGE..1
(1950 3625);
FORCEPROP 2 LAST $XR0 55 
J 0
(1699 3625);
DISPLAY 0.638298 (1699 3625);
PAINT MONO (1699 3625);
FORCEPROP 2 LAST CDS_LIB mstr_standard
J 0
(1950 3625);
PAINT MONO (1950 3625);
DISPLAY INVISIBLE (1950 3625);
FORCEPROP 1 LAST OFFPAGE TRUE
J 0
(2275 3500);
PAINT GREEN (2275 3500);
DISPLAY INVISIBLE (2275 3500);
FORCEPROP 1 LAST COMMENT_BODY TRUE
J 0
(2075 3525);
DISPLAY 1.170213 (2075 3525);
PAINT GREEN (2075 3525);
DISPLAY INVISIBLE (2075 3525);
FORCEPROP 2 LAST PATH I43
J 0
(2000 3700);
DISPLAY 1.021277 (2000 3700);
PAINT ORANGE (2000 3700);
DISPLAY INVISIBLE (2000 3700);
FORCEADD GND..1
(2675 2975);
FORCEPROP 3 LASTPIN (2675 3025) SIG_NAME GND\g
J 0
(2685 3035);
DISPLAY 0.659574 (2685 3035);
PAINT MONO (2685 3035);
DISPLAY INVISIBLE (2685 3035);
FORCEPROP 1 LAST VOLTAGE 0
J 0
(2675 2975);
PAINT SKYBLUE (2675 2975);
DISPLAY INVISIBLE (2675 2975);
FORCEPROP 2 LAST CDS_LIB mstr_symbols
J 0
(2675 2975);
PAINT MONO (2675 2975);
DISPLAY INVISIBLE (2675 2975);
FORCEPROP 1 LAST SIZE 1B
J 0
(2750 2925);
DISPLAY 1.170213 (2750 2925);
PAINT GREEN (2750 2925);
DISPLAY INVISIBLE (2750 2925);
FORCEPROP 1 LAST BODY_TYPE PLUMBING
J 0
(2630 2932);
DISPLAY 0.340426 (2630 2932);
PAINT GREEN (2630 2932);
DISPLAY INVISIBLE (2630 2932);
FORCEPROP 1 LAST PATH I44
J 0
(2750 2975);
DISPLAY 0.872340 (2750 2975);
PAINT AQUA (2750 2975);
DISPLAY INVISIBLE (2750 2975);
FORCEPROP 1 LAST HDL_POWER GND
J 0
(2675 3125);
DISPLAY 1.170213 (2675 3125);
PAINT GREEN (2675 3125);
DISPLAY INVISIBLE (2675 3125);
FORCEADD RES..1
(2675 1950);
FORCEPROP 1 LAST LOCATION R9L3
J 0
(2650 2025);
DISPLAY 0.617021 (2650 2025);
PAINT AQUA (2650 2025);
FORCEPROP 1 LAST PART_NUMBER G21796-274
J 0
(2550 1800);
DISPLAY 0.617021 (2550 1800);
PAINT BLUE (2550 1800);
FORCEPROP 1 LAST VALUE 2
J 2
(2600 1900);
DISPLAY 0.617021 (2600 1900);
PAINT SKYBLUE (2600 1900);
FORCEPROP 1 LAST TOLERANCE 1.0%
J 0
(2775 1850);
DISPLAY 0.617021 (2775 1850);
PAINT SKYBLUE (2775 1850);
FORCEPROP 1 LAST PACK_TYPE 0402
J 0
(2550 1850);
DISPLAY 0.617021 (2550 1850);
PAINT SKYBLUE (2550 1850);
FORCEPROP 1 LAST MATERIAL CHIP
J 0
(2900 1900);
DISPLAY 0.617021 (2900 1900);
PAINT SKYBLUE (2900 1900);
FORCEPROP 1 LAST WATTAGE 1/16W
J 2
(2850 1900);
DISPLAY 0.617021 (2850 1900);
PAINT SKYBLUE (2850 1900);
FORCEPROP 1 LASTPIN (2775 1950) $PN 2
J 0
(2737 1962);
DISPLAY 0.617021 (2737 1962);
PAINT MONO (2737 1962);
FORCEPROP 1 LASTPIN (2575 1950) $PN 1
J 0
(2587 1962);
DISPLAY 0.617021 (2587 1962);
PAINT MONO (2587 1962);
FORCEPROP 2 LAST BOM_COST PROC_SOCKET
J 0
(2675 1950);
PAINT MONO (2675 1950);
DISPLAY INVISIBLE (2675 1950);
FORCEPROP 2 LAST SEC_TYPE 0402
J 0
(2625 2150);
PAINT MONO (2625 2150);
DISPLAY INVISIBLE (2625 2150);
FORCEPROP 2 LAST CDS_LIB mstr_discrete
J 0
(2675 1950);
PAINT ORANGE (2675 1950);
DISPLAY INVISIBLE (2675 1950);
FORCEPROP 2 LAST SEC 1
J 0
(2625 2150);
DISPLAY 0.936170 (2625 2150);
PAINT MONO (2625 2150);
DISPLAY INVISIBLE (2625 2150);
FORCEPROP 2 LAST CDS_LOCATION R9L3
J 0
(2650 2025);
DISPLAY 0.617021 (2650 2025);
PAINT AQUA (2650 2025);
DISPLAY INVISIBLE (2650 2025);
FORCEPROP 1 LAST PATH I45
J 0
(2625 2100);
DISPLAY 0.978723 (2625 2100);
PAINT WHITE (2625 2100);
DISPLAY INVISIBLE (2625 2100);
FORCEPROP 0 LAST ROOM PROC
J 0
(2600 1875);
DISPLAY 0.617021 (2600 1875);
PAINT ORANGE (2600 1875);
DISPLAY INVISIBLE (2600 1875);
FORCEADD CAP_A..1
(2450 1650);
FORCEPROP 1 LAST LOCATION C9L3
J 0
(2500 1750);
DISPLAY 0.617021 (2500 1750);
PAINT AQUA (2500 1750);
FORCEPROP 1 LAST PART_NUMBER A36096-045
J 0
(2500 1500);
DISPLAY 0.617021 (2500 1500);
PAINT BLUE (2500 1500);
FORCEPROP 1 LAST VALUE 0.01UF
J 0
(2500 1700);
DISPLAY 0.617021 (2500 1700);
PAINT SKYBLUE (2500 1700);
FORCEPROP 1 LAST TOLERANCE 10%
J 0
(2500 1600);
DISPLAY 0.617021 (2500 1600);
PAINT SKYBLUE (2500 1600);
FORCEPROP 1 LAST PACK_TYPE 0402V
J 0
(2500 1450);
DISPLAY 0.617021 (2500 1450);
PAINT SKYBLUE (2500 1450);
FORCEPROP 1 LAST VOLTAGE 25V
J 0
(2500 1650);
DISPLAY 0.617021 (2500 1650);
PAINT SKYBLUE (2500 1650);
FORCEPROP 1 LAST MATERIAL X7R
J 0
(2500 1550);
DISPLAY 0.617021 (2500 1550);
PAINT SKYBLUE (2500 1550);
FORCEPROP 1 LASTPIN (2450 1750) $PN 1
J 0
(2460 1730);
DISPLAY 0.617021 (2460 1730);
PAINT ORANGE (2460 1730);
FORCEPROP 1 LASTPIN (2450 1550) $PN 2
J 0
(2460 1530);
DISPLAY 0.617021 (2460 1530);
PAINT ORANGE (2460 1530);
FORCEPROP 2 LAST CDS_LOCATION C9L3
J 0
(2500 1750);
DISPLAY 0.617021 (2500 1750);
PAINT AQUA (2500 1750);
DISPLAY INVISIBLE (2500 1750);
FORCEPROP 2 LAST BOM_COST SM_CONTROLLER
J 0
(2450 1650);
PAINT MONO (2450 1650);
DISPLAY INVISIBLE (2450 1650);
FORCEPROP 2 LAST CDS_LIB dev_discrete
J 0
(2450 1650);
PAINT ORANGE (2450 1650);
DISPLAY INVISIBLE (2450 1650);
FORCEPROP 2 LAST CDS_SEC 1
J 0
(2500 1800);
PAINT ORANGE (2500 1800);
DISPLAY INVISIBLE (2500 1800);
FORCEPROP 2 LAST SEC_TYPE 0402V
J 0
(2500 1850);
DISPLAY 1.021277 (2500 1850);
PAINT ORANGE (2500 1850);
DISPLAY INVISIBLE (2500 1850);
FORCEPROP 2 LAST SEC 1
J 0
(2500 1850);
DISPLAY 0.680851 (2500 1850);
PAINT MONO (2500 1850);
DISPLAY INVISIBLE (2500 1850);
FORCEPROP 1 LAST PATH I46
J 0
(2500 1800);
DISPLAY 0.978723 (2500 1800);
PAINT WHITE (2500 1800);
DISPLAY INVISIBLE (2500 1800);
FORCEPROP 0 LAST ROOM MEM
J 0
(2500 1400);
DISPLAY 0.978723 (2500 1400);
PAINT ORANGE (2500 1400);
DISPLAY INVISIBLE (2500 1400);
FORCEADD GND..1
(2675 1300);
FORCEPROP 3 LASTPIN (2675 1350) SIG_NAME GND\g
J 0
(2685 1360);
DISPLAY 0.659574 (2685 1360);
PAINT MONO (2685 1360);
DISPLAY INVISIBLE (2685 1360);
FORCEPROP 1 LAST VOLTAGE 0
J 0
(2675 1300);
PAINT SKYBLUE (2675 1300);
DISPLAY INVISIBLE (2675 1300);
FORCEPROP 2 LAST CDS_LIB mstr_symbols
J 0
(2675 1300);
PAINT MONO (2675 1300);
DISPLAY INVISIBLE (2675 1300);
FORCEPROP 1 LAST SIZE 1B
J 0
(2750 1250);
DISPLAY 1.170213 (2750 1250);
PAINT GREEN (2750 1250);
DISPLAY INVISIBLE (2750 1250);
FORCEPROP 1 LAST BODY_TYPE PLUMBING
J 0
(2630 1257);
DISPLAY 0.340426 (2630 1257);
PAINT GREEN (2630 1257);
DISPLAY INVISIBLE (2630 1257);
FORCEPROP 1 LAST PATH I47
J 0
(2750 1300);
DISPLAY 0.872340 (2750 1300);
PAINT AQUA (2750 1300);
DISPLAY INVISIBLE (2750 1300);
FORCEPROP 1 LAST HDL_POWER GND
J 0
(2675 1450);
DISPLAY 1.170213 (2675 1450);
PAINT GREEN (2675 1450);
DISPLAY INVISIBLE (2675 1450);
FORCEADD OFFPAGE..1
(1950 1950);
FORCEPROP 2 LAST $XR0 55 
J 0
(1699 1950);
DISPLAY 0.638298 (1699 1950);
PAINT MONO (1699 1950);
FORCEPROP 2 LAST CDS_LIB mstr_standard
J 0
(1950 1950);
PAINT MONO (1950 1950);
DISPLAY INVISIBLE (1950 1950);
FORCEPROP 1 LAST OFFPAGE TRUE
J 0
(2275 1825);
PAINT GREEN (2275 1825);
DISPLAY INVISIBLE (2275 1825);
FORCEPROP 1 LAST COMMENT_BODY TRUE
J 0
(2075 1850);
DISPLAY 1.170213 (2075 1850);
PAINT GREEN (2075 1850);
DISPLAY INVISIBLE (2075 1850);
FORCEPROP 2 LAST PATH I48
J 0
(2000 2025);
DISPLAY 1.021277 (2000 2025);
PAINT ORANGE (2000 2025);
DISPLAY INVISIBLE (2000 2025);
FORCEADD PVDDQ_GHJ..1
(-1900 4200);
FORCEPROP 3 LASTPIN (-1900 4150) SIG_NAME PVDDQ_GHJ\g
J 0
(-1890 4160);
DISPLAY 0.659574 (-1890 4160);
PAINT MONO (-1890 4160);
DISPLAY INVISIBLE (-1890 4160);
FORCEPROP 1 LAST VOLTAGE 1.2V
J 0
(-1945 4157);
DISPLAY 0.340426 (-1945 4157);
PAINT SKYBLUE (-1945 4157);
DISPLAY INVISIBLE (-1945 4157);
FORCEPROP 2 LAST CDS_LIB mstr_symbols
J 0
(-1900 4200);
PAINT ORANGE (-1900 4200);
DISPLAY INVISIBLE (-1900 4200);
FORCEPROP 1 LAST BODY_TYPE PLUMBING
J 0
(-1945 4157);
DISPLAY 0.340426 (-1945 4157);
PAINT GREEN (-1945 4157);
DISPLAY INVISIBLE (-1945 4157);
FORCEPROP 1 LAST PATH I5
J 0
(-1850 4225);
DISPLAY 0.872340 (-1850 4225);
PAINT AQUA (-1850 4225);
DISPLAY INVISIBLE (-1850 4225);
FORCEPROP 1 LAST HDL_POWER PVDDQ_GHJ
J 1
(-1900 4250);
DISPLAY 0.872340 (-1900 4250);
PAINT GREEN (-1900 4250);
DISPLAY INVISIBLE (-1900 4250);
FORCEADD RES..2
R 2
(-1900 3950);
FORCEPROP 1 LAST LOCATION R1F5
J 2
(-1945 4075);
DISPLAY 0.617021 (-1945 4075);
PAINT AQUA (-1945 4075);
FORCEPROP 1 LAST PART_NUMBER G21796-026
J 2
(-1940 3825);
DISPLAY 0.617021 (-1940 3825);
PAINT BLUE (-1940 3825);
FORCEPROP 1 LAST VALUE 1.00K
J 2
(-1945 4025);
DISPLAY 0.617021 (-1945 4025);
PAINT SKYBLUE (-1945 4025);
FORCEPROP 1 LAST TOLERANCE 1%
J 2
(-1945 3975);
DISPLAY 0.617021 (-1945 3975);
PAINT SKYBLUE (-1945 3975);
FORCEPROP 1 LAST PACK_TYPE 0402
J 2
(-1940 3775);
DISPLAY 0.617021 (-1940 3775);
PAINT SKYBLUE (-1940 3775);
FORCEPROP 1 LAST MATERIAL CHIP
J 2
(-1940 3875);
DISPLAY 0.617021 (-1940 3875);
PAINT SKYBLUE (-1940 3875);
FORCEPROP 1 LAST WATTAGE 1/16W
J 2
(-1940 3925);
DISPLAY 0.617021 (-1940 3925);
PAINT SKYBLUE (-1940 3925);
FORCEPROP 1 LASTPIN (-1900 3850) $PN 2
J 2
(-1905 3860);
DISPLAY 0.617021 (-1905 3860);
PAINT ORANGE (-1905 3860);
FORCEPROP 1 LASTPIN (-1900 4050) $PN 1
J 2
(-1905 4012);
DISPLAY 0.617021 (-1905 4012);
PAINT ORANGE (-1905 4012);
FORCEPROP 2 LAST CDS_LIB mstr_discrete
J 0
(-1900 3950);
PAINT ORANGE (-1900 3950);
DISPLAY INVISIBLE (-1900 3950);
FORCEPROP 2 LAST BOM_COST SM_CONTROLLER
J 2
(-1900 3950);
PAINT MONO (-1900 3950);
DISPLAY INVISIBLE (-1900 3950);
FORCEPROP 2 LAST SEC_TYPE 0402
J 0
(-1950 4175);
DISPLAY 1.021277 (-1950 4175);
PAINT ORANGE (-1950 4175);
DISPLAY INVISIBLE (-1950 4175);
FORCEPROP 2 LAST SEC 1
J 0
(-1950 4175);
DISPLAY 0.680851 (-1950 4175);
PAINT MONO (-1950 4175);
DISPLAY INVISIBLE (-1950 4175);
FORCEPROP 2 LAST CDS_LOCATION R1F5
J 2
(-1945 4075);
DISPLAY 0.617021 (-1945 4075);
PAINT AQUA (-1945 4075);
DISPLAY INVISIBLE (-1945 4075);
FORCEPROP 1 LAST PATH I6
J 2
(-1950 4125);
DISPLAY 0.978723 (-1950 4125);
PAINT WHITE (-1950 4125);
DISPLAY INVISIBLE (-1950 4125);
FORCEPROP 2 LAST ROOM MEM
J 2
(-1950 4125);
PAINT PEACH (-1950 4125);
DISPLAY INVISIBLE (-1950 4125);
FORCEADD RES..1
(-2125 3625);
FORCEPROP 1 LAST LOCATION R1F4
J 0
(-2175 3675);
DISPLAY 0.617021 (-2175 3675);
PAINT AQUA (-2175 3675);
FORCEPROP 1 LAST PART_NUMBER G21796-274
J 0
(-2250 3475);
DISPLAY 0.617021 (-2250 3475);
PAINT BLUE (-2250 3475);
FORCEPROP 1 LAST VALUE 2
J 2
(-2200 3575);
DISPLAY 0.617021 (-2200 3575);
PAINT SKYBLUE (-2200 3575);
FORCEPROP 1 LAST TOLERANCE 1.0%
J 0
(-2025 3525);
DISPLAY 0.617021 (-2025 3525);
PAINT SKYBLUE (-2025 3525);
FORCEPROP 1 LAST PACK_TYPE 0402
J 0
(-2250 3525);
DISPLAY 0.617021 (-2250 3525);
PAINT SKYBLUE (-2250 3525);
FORCEPROP 1 LAST MATERIAL CHIP
J 0
(-1900 3575);
DISPLAY 0.617021 (-1900 3575);
PAINT SKYBLUE (-1900 3575);
FORCEPROP 1 LAST WATTAGE 1/16W
J 2
(-1950 3575);
DISPLAY 0.617021 (-1950 3575);
PAINT SKYBLUE (-1950 3575);
FORCEPROP 1 LASTPIN (-2025 3625) $PN 2
J 0
(-2063 3637);
DISPLAY 0.617021 (-2063 3637);
PAINT ORANGE (-2063 3637);
FORCEPROP 1 LASTPIN (-2225 3625) $PN 1
J 0
(-2213 3637);
DISPLAY 0.617021 (-2213 3637);
PAINT ORANGE (-2213 3637);
FORCEPROP 2 LAST BOM_COST PROC_SOCKET
J 0
(-2125 3625);
PAINT MONO (-2125 3625);
DISPLAY INVISIBLE (-2125 3625);
FORCEPROP 2 LAST CDS_LIB mstr_discrete
J 0
(-2125 3625);
PAINT ORANGE (-2125 3625);
DISPLAY INVISIBLE (-2125 3625);
FORCEPROP 2 LAST SEC_TYPE 0402
J 0
(-2175 3825);
DISPLAY 1.021277 (-2175 3825);
PAINT ORANGE (-2175 3825);
DISPLAY INVISIBLE (-2175 3825);
FORCEPROP 2 LAST SEC 1
J 0
(-2175 3825);
DISPLAY 0.680851 (-2175 3825);
PAINT MONO (-2175 3825);
DISPLAY INVISIBLE (-2175 3825);
FORCEPROP 2 LAST CDS_LOCATION R1F4
J 0
(-2175 3675);
DISPLAY 0.617021 (-2175 3675);
PAINT AQUA (-2175 3675);
DISPLAY INVISIBLE (-2175 3675);
FORCEPROP 1 LAST PATH I7
J 0
(-2175 3775);
DISPLAY 0.978723 (-2175 3775);
PAINT WHITE (-2175 3775);
DISPLAY INVISIBLE (-2175 3775);
FORCEPROP 0 LAST ROOM PROC
J 0
(-2200 3550);
DISPLAY 0.617021 (-2200 3550);
PAINT ORANGE (-2200 3550);
DISPLAY INVISIBLE (-2200 3550);
FORCEADD CAP_A..1
(-2350 3325);
FORCEPROP 1 LAST LOCATION C1F19
J 0
(-2300 3425);
DISPLAY 0.617021 (-2300 3425);
PAINT AQUA (-2300 3425);
FORCEPROP 1 LAST PART_NUMBER A36096-045
J 0
(-2300 3175);
DISPLAY 0.617021 (-2300 3175);
PAINT BLUE (-2300 3175);
FORCEPROP 1 LAST VALUE 0.01UF
J 0
(-2300 3375);
DISPLAY 0.617021 (-2300 3375);
PAINT SKYBLUE (-2300 3375);
FORCEPROP 1 LAST TOLERANCE 10%
J 0
(-2300 3275);
DISPLAY 0.617021 (-2300 3275);
PAINT SKYBLUE (-2300 3275);
FORCEPROP 1 LAST PACK_TYPE 0402V
J 0
(-2300 3125);
DISPLAY 0.617021 (-2300 3125);
PAINT SKYBLUE (-2300 3125);
FORCEPROP 1 LAST VOLTAGE 25V
J 0
(-2300 3325);
DISPLAY 0.617021 (-2300 3325);
PAINT SKYBLUE (-2300 3325);
FORCEPROP 1 LAST MATERIAL X7R
J 0
(-2300 3225);
DISPLAY 0.617021 (-2300 3225);
PAINT SKYBLUE (-2300 3225);
FORCEPROP 1 LASTPIN (-2350 3425) $PN 1
J 0
(-2340 3405);
DISPLAY 0.617021 (-2340 3405);
PAINT ORANGE (-2340 3405);
FORCEPROP 1 LASTPIN (-2350 3225) $PN 2
J 0
(-2340 3205);
DISPLAY 0.617021 (-2340 3205);
PAINT ORANGE (-2340 3205);
FORCEPROP 2 LAST CDS_LOCATION C1F19
J 0
(-2300 3425);
DISPLAY 0.617021 (-2300 3425);
PAINT AQUA (-2300 3425);
DISPLAY INVISIBLE (-2300 3425);
FORCEPROP 2 LAST BOM_COST PROC_SOCKET
J 0
(-2350 3325);
PAINT MONO (-2350 3325);
DISPLAY INVISIBLE (-2350 3325);
FORCEPROP 2 LAST CDS_LIB dev_discrete
J 0
(-2350 3325);
PAINT ORANGE (-2350 3325);
DISPLAY INVISIBLE (-2350 3325);
FORCEPROP 2 LAST CDS_SEC 1
J 0
(-2300 3475);
PAINT ORANGE (-2300 3475);
DISPLAY INVISIBLE (-2300 3475);
FORCEPROP 2 LAST SEC_TYPE 0402V
J 0
(-2300 3525);
DISPLAY 1.021277 (-2300 3525);
PAINT ORANGE (-2300 3525);
DISPLAY INVISIBLE (-2300 3525);
FORCEPROP 2 LAST SEC 1
J 0
(-2300 3525);
DISPLAY 0.680851 (-2300 3525);
PAINT MONO (-2300 3525);
DISPLAY INVISIBLE (-2300 3525);
FORCEPROP 1 LAST PATH I8
J 0
(-2300 3475);
DISPLAY 0.978723 (-2300 3475);
PAINT WHITE (-2300 3475);
DISPLAY INVISIBLE (-2300 3475);
FORCEPROP 0 LAST ROOM PROC
J 0
(-2300 3075);
DISPLAY 0.978723 (-2300 3075);
PAINT ORANGE (-2300 3075);
DISPLAY INVISIBLE (-2300 3075);
FORCEADD GND..1
(-2125 2975);
FORCEPROP 3 LASTPIN (-2125 3025) SIG_NAME GND\g
J 0
(-2115 3035);
DISPLAY 0.659574 (-2115 3035);
PAINT MONO (-2115 3035);
DISPLAY INVISIBLE (-2115 3035);
FORCEPROP 1 LAST VOLTAGE 0
J 0
(-2125 2975);
PAINT SKYBLUE (-2125 2975);
DISPLAY INVISIBLE (-2125 2975);
FORCEPROP 1 LAST SIZE 1B
J 0
(-2050 2925);
DISPLAY 1.170213 (-2050 2925);
PAINT GREEN (-2050 2925);
DISPLAY INVISIBLE (-2050 2925);
FORCEPROP 2 LAST CDS_LIB mstr_symbols
J 0
(-2125 2975);
PAINT MONO (-2125 2975);
DISPLAY INVISIBLE (-2125 2975);
FORCEPROP 1 LAST BODY_TYPE PLUMBING
J 0
(-2170 2932);
DISPLAY 0.340426 (-2170 2932);
PAINT GREEN (-2170 2932);
DISPLAY INVISIBLE (-2170 2932);
FORCEPROP 1 LAST PATH I9
J 0
(-2050 2975);
DISPLAY 0.872340 (-2050 2975);
PAINT AQUA (-2050 2975);
DISPLAY INVISIBLE (-2050 2975);
FORCEPROP 1 LAST HDL_POWER GND
J 0
(-2125 3125);
DISPLAY 1.170213 (-2125 3125);
PAINT GREEN (-2125 3125);
DISPLAY INVISIBLE (-2125 3125);
FORCEADD CAD_NOTE..1
(-825 2800);
FORCEPROP 0 LAST L1 PLACE BETWEEN DIMM_L1 & L2
J 0
(-975 2675);
PAINT WHITE (-975 2675);
FORCEPROP 2 LAST CDS_LIB mstr_symbols
J 0
(-825 2800);
PAINT WHITE (-825 2800);
DISPLAY INVISIBLE (-825 2800);
FORCEPROP 2 LAST BOM_COST SM_CONTROLLER
J 0
(-975 2750);
PAINT WHITE (-975 2750);
DISPLAY INVISIBLE (-975 2750);
FORCEPROP 1 LAST COMMENT_BODY TRUE
J 0
(-800 2900);
DISPLAY 1.319149 (-800 2900);
PAINT WHITE (-800 2900);
DISPLAY INVISIBLE (-800 2900);
FORCEPROP 2 LAST ROOM BMC
J 0
(-975 2750);
PAINT WHITE (-975 2750);
DISPLAY INVISIBLE (-975 2750);
FORCEADD CAD_NOTE..1
(1625 2800);
FORCEPROP 0 LAST L1 PLACE BETWEEN DIMM_M1 & M2
J 0
(1500 2700);
PAINT WHITE (1500 2700);
FORCEPROP 2 LAST CDS_LIB mstr_symbols
J 0
(1625 2800);
PAINT WHITE (1625 2800);
DISPLAY INVISIBLE (1625 2800);
FORCEPROP 2 LAST BOM_COST SM_CONTROLLER
J 0
(1475 2750);
PAINT WHITE (1475 2750);
DISPLAY INVISIBLE (1475 2750);
FORCEPROP 1 LAST COMMENT_BODY TRUE
J 0
(1650 2900);
DISPLAY 1.319149 (1650 2900);
PAINT WHITE (1650 2900);
DISPLAY INVISIBLE (1650 2900);
FORCEPROP 2 LAST ROOM BMC
J 0
(1475 2750);
PAINT WHITE (1475 2750);
DISPLAY INVISIBLE (1475 2750);
FORCEADD CAD_NOTE..1
(1625 4475);
FORCEPROP 0 LAST L1 PLACE BETWEEN DIMM_ J1 & J2
J 0
(1475 4375);
PAINT WHITE (1475 4375);
FORCEPROP 2 LAST CDS_LIB mstr_symbols
J 0
(1625 4475);
PAINT WHITE (1625 4475);
DISPLAY INVISIBLE (1625 4475);
FORCEPROP 2 LAST BOM_COST SM_CONTROLLER
J 0
(1475 4425);
PAINT WHITE (1475 4425);
DISPLAY INVISIBLE (1475 4425);
FORCEPROP 1 LAST COMMENT_BODY TRUE
J 0
(1650 4575);
DISPLAY 1.319149 (1650 4575);
PAINT WHITE (1650 4575);
DISPLAY INVISIBLE (1650 4575);
FORCEPROP 2 LAST ROOM BMC
J 0
(1475 4425);
PAINT WHITE (1475 4425);
DISPLAY INVISIBLE (1475 4425);
FORCEADD CAD_NOTE..1
(-825 4475);
FORCEPROP 0 LAST L1 PLACE BETWEEN DIMM_H1 & H2
J 0
(-975 4350);
PAINT WHITE (-975 4350);
FORCEPROP 2 LAST CDS_LIB mstr_symbols
J 0
(-825 4475);
PAINT WHITE (-825 4475);
DISPLAY INVISIBLE (-825 4475);
FORCEPROP 2 LAST BOM_COST SM_CONTROLLER
J 0
(-975 4425);
PAINT WHITE (-975 4425);
DISPLAY INVISIBLE (-975 4425);
FORCEPROP 1 LAST COMMENT_BODY TRUE
J 0
(-800 4575);
DISPLAY 1.319149 (-800 4575);
PAINT WHITE (-800 4575);
DISPLAY INVISIBLE (-800 4575);
FORCEPROP 2 LAST ROOM BMC
J 0
(-975 4425);
PAINT WHITE (-975 4425);
DISPLAY INVISIBLE (-975 4425);
FORCEADD INTEL_CORP_BPAGE..1
(4250 200);
FORCEPROP 1 LAST CDS_CON_LAST_MODIFIED Fri Jun 16 17:48:40 2017
J 0
(2825 525);
PAINT ORANGE (2825 525);
DISPLAY INVISIBLE (2825 525);
FORCEPROP 1 LAST CUSTOM_TXT_CDS <CURRENT_DESIGN_SHEET> OF <TOTAL_DESIGN_SHEETS>
J 0
(3750 225);
PAINT ORANGE (3750 225);
FORCEPROP 1 LAST CUSTOM_TXT_CDS <CON_LAST_MODIFIED>
J 0
(250 300);
PAINT ORANGE (250 300);
FORCEPROP 2 LAST CUSTOM_TXT_CDS <XR_PAGE_TITLE>
J 0
(-3640 5450);
DISPLAY 0.638298 (-3640 5450);
PAINT PINK (-3640 5450);
DISPLAY INVISIBLE (-3640 5450);
FORCEPROP 1 LAST SCH_TITLE CPU SIDE BAND:CPU1 DIMM CA VREF
J 0
(-3700 250);
DISPLAY 1.212766 (-3700 250);
PAINT ORANGE (-3700 250);
FORCEPROP 2 LAST PAGE_BORDER TRUE
J 0
(-3640 5450);
DISPLAY 0.638298 (-3640 5450);
PAINT PINK (-3640 5450);
DISPLAY INVISIBLE (-3640 5450);
FORCEPROP 2 LAST CDS_LIB mstr_symbols
J 0
(4250 200);
PAINT MONO (4250 200);
DISPLAY INVISIBLE (4250 200);
FORCEPROP 1 LAST COMMENT_BODY TRUE
J 0
(4262 212);
DISPLAY 0.468085 (4262 212);
PAINT GREEN (4262 212);
DISPLAY INVISIBLE (4262 212);
FORCEPROP 2 LAST CDS_XR_PAGE_TITLE CR-100 : @BASEBOARD_FAB2_LIB.BASEBOARD_FAB2(SCH_1):PAGE100
J 0
(-3640 5450);
DISPLAY 0.638298 (-3640 5450);
PAINT PINK (-3640 5450);
DISPLAY INVISIBLE (-3640 5450);
FORCEADD CAD_NOTE..1
(-3175 2800);
FORCEPROP 0 LAST L1 PLACE BETWEEN DIMM_K1 & K2
J 0
(-3350 2650);
PAINT WHITE (-3350 2650);
FORCEPROP 2 LAST BOM_COST SM_CONTROLLER
J 0
(-3325 2750);
PAINT WHITE (-3325 2750);
DISPLAY INVISIBLE (-3325 2750);
FORCEPROP 2 LAST CDS_LIB mstr_symbols
J 0
(-3175 2800);
PAINT WHITE (-3175 2800);
DISPLAY INVISIBLE (-3175 2800);
FORCEPROP 1 LAST COMMENT_BODY TRUE
J 0
(-3150 2900);
DISPLAY 1.319149 (-3150 2900);
PAINT WHITE (-3150 2900);
DISPLAY INVISIBLE (-3150 2900);
FORCEPROP 2 LAST ROOM BMC
J 0
(-3325 2750);
PAINT WHITE (-3325 2750);
DISPLAY INVISIBLE (-3325 2750);
FORCEADD CAD_NOTE..1
(-3175 4475);
FORCEPROP 0 LAST L1 PLACE BETWEEN DIMM_G1 & G2
J 0
(-3325 4325);
PAINT WHITE (-3325 4325);
FORCEPROP 2 LAST BOM_COST SM_CONTROLLER
J 0
(-3325 4425);
PAINT WHITE (-3325 4425);
DISPLAY INVISIBLE (-3325 4425);
FORCEPROP 2 LAST CDS_LIB mstr_symbols
J 0
(-3175 4475);
PAINT WHITE (-3175 4475);
DISPLAY INVISIBLE (-3175 4475);
FORCEPROP 1 LAST COMMENT_BODY TRUE
J 0
(-3150 4575);
DISPLAY 1.319149 (-3150 4575);
PAINT WHITE (-3150 4575);
DISPLAY INVISIBLE (-3150 4575);
FORCEPROP 2 LAST ROOM BMC
J 0
(-3325 4425);
PAINT WHITE (-3325 4425);
DISPLAY INVISIBLE (-3325 4425);
WIRE 16 -1 (-1900 2475)(-1900 2375);
WIRE 16 -1 (-2125 1425)(-2125 1350);
WIRE 16 -1 (-2125 1425)(-1825 1425);
WIRE 16 -1 (-2350 1425)(-2125 1425);
WIRE 16 -1 (-2350 1550)(-2350 1425);
WIRE 16 -1 (-1825 1425)(-1825 1525);
WIRE 16 -1 (450 4150)(450 4050);
WIRE 16 -1 (450 2475)(450 2375);
WIRE 16 -1 (225 3100)(225 3025);
WIRE 16 -1 (225 3100)(525 3100);
WIRE 16 -1 (225 3100)(0 3100);
WIRE 16 -1 (0 3225)(0 3100);
WIRE 16 -1 (525 3100)(525 3200);
WIRE 16 -1 (225 1425)(225 1350);
WIRE 16 -1 (225 1425)(525 1425);
WIRE 16 -1 (0 1425)(225 1425);
WIRE 16 -1 (0 1550)(0 1425);
WIRE 16 -1 (525 1425)(525 1525);
WIRE 16 -1 (2900 4150)(2900 4050);
WIRE 16 -1 (2900 2475)(2900 2375);
WIRE 16 -1 (2675 3100)(2675 3025);
WIRE 16 -1 (2675 3100)(2975 3100);
WIRE 16 -1 (2675 3100)(2450 3100);
WIRE 16 -1 (2450 3225)(2450 3100);
WIRE 16 -1 (2975 3100)(2975 3200);
WIRE 16 -1 (2675 1425)(2675 1350);
WIRE 16 -1 (2675 1425)(2975 1425);
WIRE 16 -1 (2450 1425)(2675 1425);
WIRE 16 -1 (2450 1550)(2450 1425);
WIRE 16 -1 (2975 1425)(2975 1525);
WIRE 16 -1 (-1900 4150)(-1900 4050);
WIRE 16 -1 (-2125 3100)(-2125 3025);
WIRE 16 -1 (-2125 3100)(-1825 3100);
WIRE 16 -1 (-2125 3100)(-2350 3100);
WIRE 16 -1 (-2350 3225)(-2350 3100);
WIRE 16 -1 (-1825 3100)(-1825 3200);
WIRE 16 -1 (-1825 3400)(-1825 3625);
WIRE 16 -1 (-1525 3625)(-1825 3625);
WIRE 16 -1 (-2025 3625)(-1900 3625);
WIRE 16 -1 (-1825 3625)(-1900 3625);
FORCEPROP 2 LAST SIG_NAME M_G_VREF
J 0
(-1850 3635);
DISPLAY 0.617021 (-1850 3635);
PAINT ORANGE (-1850 3635);
WIRE 16 -1 (-1900 3625)(-1900 3850);
WIRE 16 -1 (-2350 1950)(-2800 1950);
FORCEPROP 2 LAST SIG_NAME M_K_CPU_VREF
J 0
(-2725 1960);
DISPLAY 0.617021 (-2725 1960);
PAINT ORANGE (-2725 1960);
WIRE 16 -1 (-2350 1750)(-2350 1950);
WIRE 16 -1 (-2350 1950)(-2225 1950);
WIRE 16 -1 (-2350 3625)(-2800 3625);
FORCEPROP 2 LAST SIG_NAME M_G_CPU_VREF
J 0
(-2725 3635);
DISPLAY 0.617021 (-2725 3635);
PAINT ORANGE (-2725 3635);
WIRE 16 -1 (-2350 3425)(-2350 3625);
WIRE 16 -1 (-2350 3625)(-2225 3625);
WIRE 16 -1 (-1825 1725)(-1825 1950);
WIRE 16 -1 (-1525 1950)(-1825 1950);
WIRE 16 -1 (-1825 1950)(-1900 1950);
FORCEPROP 2 LAST SIG_NAME M_K_VREF
J 0
(-1850 1960);
DISPLAY 0.617021 (-1850 1960);
PAINT ORANGE (-1850 1960);
WIRE 16 -1 (-1900 1950)(-1900 2175);
WIRE 16 -1 (-2025 1950)(-1900 1950);
WIRE 16 -1 (0 3425)(0 3625);
WIRE 16 -1 (0 3625)(-450 3625);
FORCEPROP 2 LAST SIG_NAME M_H_CPU_VREF
J 0
(-375 3635);
DISPLAY 0.617021 (-375 3635);
PAINT ORANGE (-375 3635);
WIRE 16 -1 (0 3625)(125 3625);
WIRE 16 -1 (0 1750)(0 1950);
WIRE 16 -1 (0 1950)(-450 1950);
FORCEPROP 2 LAST SIG_NAME M_L_CPU_VREF
J 0
(-375 1960);
DISPLAY 0.617021 (-375 1960);
PAINT ORANGE (-375 1960);
WIRE 16 -1 (0 1950)(125 1950);
WIRE 16 -1 (525 1725)(525 1950);
WIRE 16 -1 (825 1950)(525 1950);
WIRE 16 -1 (525 1950)(450 1950);
FORCEPROP 2 LAST SIG_NAME M_L_VREF
J 0
(500 1960);
DISPLAY 0.617021 (500 1960);
PAINT ORANGE (500 1960);
WIRE 16 -1 (450 1950)(450 2175);
WIRE 16 -1 (325 1950)(450 1950);
WIRE 16 -1 (325 3625)(450 3625);
WIRE 16 -1 (450 3625)(450 3850);
WIRE 16 -1 (525 3625)(450 3625);
FORCEPROP 2 LAST SIG_NAME M_H_VREF
J 0
(500 3635);
DISPLAY 0.617021 (500 3635);
PAINT ORANGE (500 3635);
WIRE 16 -1 (825 3625)(525 3625);
WIRE 16 -1 (525 3400)(525 3625);
WIRE 16 -1 (2450 1950)(2000 1950);
FORCEPROP 2 LAST SIG_NAME M_M_CPU_VREF
J 0
(2075 1960);
DISPLAY 0.617021 (2075 1960);
PAINT ORANGE (2075 1960);
WIRE 16 -1 (2450 1750)(2450 1950);
WIRE 16 -1 (2450 1950)(2575 1950);
WIRE 16 -1 (2975 1725)(2975 1950);
WIRE 16 -1 (3275 1950)(2975 1950);
WIRE 16 -1 (2975 1950)(2900 1950);
FORCEPROP 2 LAST SIG_NAME M_M_VREF
J 0
(2950 1960);
DISPLAY 0.617021 (2950 1960);
PAINT ORANGE (2950 1960);
WIRE 16 -1 (2900 1950)(2900 2175);
WIRE 16 -1 (2775 1950)(2900 1950);
WIRE 16 -1 (2450 3625)(2000 3625);
FORCEPROP 2 LAST SIG_NAME M_J_CPU_VREF
J 0
(2075 3635);
DISPLAY 0.617021 (2075 3635);
PAINT ORANGE (2075 3635);
WIRE 16 -1 (2450 3425)(2450 3625);
WIRE 16 -1 (2450 3625)(2575 3625);
WIRE 16 -1 (2775 3625)(2900 3625);
WIRE 16 -1 (2900 3625)(2900 3850);
WIRE 16 -1 (2975 3625)(2900 3625);
FORCEPROP 2 LAST SIG_NAME M_J_VREF
J 0
(2950 3635);
DISPLAY 0.617021 (2950 3635);
PAINT ORANGE (2950 3635);
WIRE 16 -1 (3275 3625)(2975 3625);
WIRE 16 -1 (2975 3400)(2975 3625);
DOT 1 (-2125 1425);
DOT 1 (-2350 1950);
DOT 1 (-2125 3100);
DOT 1 (-2350 3625);
DOT 1 (-1825 1950);
DOT 1 (-1900 1950);
DOT 1 (-1900 3625);
DOT 1 (-1825 3625);
DOT 1 (525 3625);
DOT 1 (450 3625);
DOT 1 (450 1950);
DOT 1 (525 1950);
DOT 1 (225 3100);
DOT 1 (0 1950);
DOT 1 (225 1425);
DOT 1 (2975 3625);
DOT 1 (2900 3625);
DOT 1 (2900 1950);
DOT 1 (2975 1950);
DOT 1 (2450 3625);
DOT 1 (2675 3100);
DOT 1 (2675 1425);
DOT 1 (0 3625);
DOT 1 (2450 1950);
QUIT
